FILE_TYPE = MACRO_DRAWING;
SET COLOR_WIRE YELLOW;
SET COLOR_PROP MONO;
SET COLOR_DOT WHITE;
SET COLOR_ARC YELLOW;
SET COLOR_BODY GREEN;
SET COLOR_NOTE MONO;
SET PROP_DISPLAY VALUE;
SET PAGE_NUMBER P42;
FORCEADD CAP..1
(-2550 950);
FORCEPROP 1 LAST LOCATION C4P1
J 0
(-2500 1050);
DISPLAY 0.617021 (-2500 1050);
PAINT AQUA (-2500 1050);
FORCEPROP 1 LAST PART_NUMBER C95333-006
R 1
J 0
(-2600 775);
DISPLAY 0.617021 (-2600 775);
PAINT BLUE (-2600 775);
FORCEPROP 1 LAST VALUE 47UF
J 0
(-2500 1000);
DISPLAY 0.617021 (-2500 1000);
PAINT SKYBLUE (-2500 1000);
FORCEPROP 1 LAST TOLERANCE 20%
J 0
(-2500 900);
DISPLAY 0.617021 (-2500 900);
PAINT SKYBLUE (-2500 900);
FORCEPROP 1 LAST PACK_TYPE 0805
J 0
(-2500 800);
DISPLAY 0.617021 (-2500 800);
PAINT SKYBLUE (-2500 800);
FORCEPROP 1 LASTPIN (-2550 850) $PN 2
J 0
(-2540 830);
DISPLAY 0.617021 (-2540 830);
PAINT ORANGE (-2540 830);
FORCEPROP 1 LASTPIN (-2550 1050) $PN 1
J 0
(-2540 1030);
DISPLAY 0.617021 (-2540 1030);
PAINT ORANGE (-2540 1030);
FORCEPROP 1 LAST VOLTAGE 4V
J 0
(-2500 950);
PAINT SKYBLUE (-2500 950);
DISPLAY INVISIBLE (-2500 950);
FORCEPROP 1 LAST MATERIAL X6S
J 0
(-2500 850);
PAINT SKYBLUE (-2500 850);
DISPLAY INVISIBLE (-2500 850);
FORCEPROP 2 LAST BOM_COST PROC_SOCKET
J 0
(-2500 1150);
DISPLAY 1.021277 (-2500 1150);
PAINT ORANGE (-2500 1150);
DISPLAY INVISIBLE (-2500 1150);
FORCEPROP 2 LAST CDS_LIB mstr_discrete
J 0
(-2550 950);
PAINT ORANGE (-2550 950);
DISPLAY INVISIBLE (-2550 950);
FORCEPROP 2 LAST CDS_SEC 1
J 0
(-2490 1170);
PAINT MONO (-2490 1170);
DISPLAY INVISIBLE (-2490 1170);
FORCEPROP 2 LAST $SEC 1
J 0
(-2490 1170);
PAINT MONO (-2490 1170);
DISPLAY INVISIBLE (-2490 1170);
FORCEPROP 2 LAST CDS_LOCATION C4P1
J 0
(-2500 1050);
DISPLAY 0.617021 (-2500 1050);
PAINT AQUA (-2500 1050);
DISPLAY INVISIBLE (-2500 1050);
FORCEPROP 1 LAST PATH I10
J 0
(-2500 1100);
DISPLAY 0.978723 (-2500 1100);
PAINT WHITE (-2500 1100);
DISPLAY INVISIBLE (-2500 1100);
FORCEPROP 2 LAST ROOM PVCCIN_CPU0_DECAP_VR
J 0
(-2500 1100);
DISPLAY 1.021277 (-2500 1100);
PAINT ORANGE (-2500 1100);
DISPLAY INVISIBLE (-2500 1100);
FORCEADD CAP_A..1
(-4700 3775);
FORCEPROP 1 LAST LOCATION C5D28
J 0
(-4650 3875);
DISPLAY 0.617021 (-4650 3875);
PAINT AQUA (-4650 3875);
FORCEPROP 1 LAST PART_NUMBER E15431-004
J 0
(-4650 3625);
DISPLAY 0.617021 (-4650 3625);
PAINT BLUE (-4650 3625);
FORCEPROP 1 LAST VALUE 22.0UF
J 0
(-4650 3825);
DISPLAY 0.617021 (-4650 3825);
PAINT SKYBLUE (-4650 3825);
FORCEPROP 1 LAST TOLERANCE 20%
J 0
(-4650 3725);
DISPLAY 0.617021 (-4650 3725);
PAINT SKYBLUE (-4650 3725);
FORCEPROP 1 LAST PACK_TYPE 0603V
J 0
(-4650 3575);
DISPLAY 0.617021 (-4650 3575);
PAINT SKYBLUE (-4650 3575);
FORCEPROP 1 LAST VOLTAGE 4V
J 0
(-4650 3775);
DISPLAY 0.617021 (-4650 3775);
PAINT SKYBLUE (-4650 3775);
FORCEPROP 1 LAST MATERIAL X6S
J 0
(-4650 3675);
DISPLAY 0.617021 (-4650 3675);
PAINT SKYBLUE (-4650 3675);
FORCEPROP 1 LASTPIN (-4700 3875) $PN 1
J 0
(-4690 3855);
DISPLAY 0.617021 (-4690 3855);
PAINT GREEN (-4690 3855);
FORCEPROP 1 LASTPIN (-4700 3675) $PN 2
J 0
(-4690 3655);
DISPLAY 0.617021 (-4690 3655);
PAINT GREEN (-4690 3655);
FORCEPROP 2 LAST CDS_LOCATION C5D28
J 0
(-4650 3875);
DISPLAY 0.617021 (-4650 3875);
PAINT AQUA (-4650 3875);
DISPLAY INVISIBLE (-4650 3875);
FORCEPROP 2 LAST BOM_COST PROC_SOCKET
J 0
(-4650 3975);
DISPLAY 1.021277 (-4650 3975);
PAINT ORANGE (-4650 3975);
DISPLAY INVISIBLE (-4650 3975);
FORCEPROP 2 LAST CDS_LIB dev_discrete
J 0
(-4700 3775);
PAINT ORANGE (-4700 3775);
DISPLAY INVISIBLE (-4700 3775);
FORCEPROP 2 LAST CDS_SEC 1
J 0
(-4650 3975);
PAINT MONO (-4650 3975);
DISPLAY INVISIBLE (-4650 3975);
FORCEPROP 2 LAST $SEC 1
J 0
(-4650 3975);
PAINT MONO (-4650 3975);
DISPLAY INVISIBLE (-4650 3975);
FORCEPROP 1 LAST PATH I100
J 0
(-4650 3925);
DISPLAY 0.978723 (-4650 3925);
PAINT WHITE (-4650 3925);
DISPLAY INVISIBLE (-4650 3925);
FORCEPROP 2 LAST ROOM PVCCIN_CPU0_DECAP_VR
J 0
(-4650 3925);
DISPLAY 1.021277 (-4650 3925);
PAINT ORANGE (-4650 3925);
DISPLAY INVISIBLE (-4650 3925);
FORCEADD GND..1
(-4425 3475);
FORCEPROP 3 LASTPIN (-4425 3525) SIG_NAME GND\g
J 0
(-4415 3535);
DISPLAY 0.659574 (-4415 3535);
PAINT MONO (-4415 3535);
DISPLAY INVISIBLE (-4415 3535);
FORCEPROP 1 LAST VOLTAGE 0
J 0
(-4425 3475);
PAINT SKYBLUE (-4425 3475);
DISPLAY INVISIBLE (-4425 3475);
FORCEPROP 2 LAST CDS_LIB mstr_symbols
J 0
(-4425 3475);
PAINT ORANGE (-4425 3475);
DISPLAY INVISIBLE (-4425 3475);
FORCEPROP 1 LAST SIZE 1B
J 0
(-4350 3425);
DISPLAY 0.893617 (-4350 3425);
PAINT GREEN (-4350 3425);
DISPLAY INVISIBLE (-4350 3425);
FORCEPROP 1 LAST BODY_TYPE PLUMBING
J 0
(-4470 3432);
DISPLAY 0.340426 (-4470 3432);
PAINT GREEN (-4470 3432);
DISPLAY INVISIBLE (-4470 3432);
FORCEPROP 1 LAST PATH I101
J 0
(-4350 3475);
DISPLAY 0.872340 (-4350 3475);
PAINT AQUA (-4350 3475);
DISPLAY INVISIBLE (-4350 3475);
FORCEPROP 1 LAST HDL_POWER GND
J 0
(-4425 3625);
DISPLAY 0.893617 (-4425 3625);
PAINT GREEN (-4425 3625);
DISPLAY INVISIBLE (-4425 3625);
FORCEADD CAP_A..1
(-4700 4450);
FORCEPROP 1 LAST LOCATION C5D29
J 0
(-4650 4550);
DISPLAY 0.617021 (-4650 4550);
PAINT AQUA (-4650 4550);
FORCEPROP 1 LAST PART_NUMBER E15431-004
J 0
(-4650 4300);
DISPLAY 0.617021 (-4650 4300);
PAINT BLUE (-4650 4300);
FORCEPROP 1 LAST VALUE 22.0UF
J 0
(-4650 4500);
DISPLAY 0.617021 (-4650 4500);
PAINT SKYBLUE (-4650 4500);
FORCEPROP 1 LAST TOLERANCE 20%
J 0
(-4650 4400);
DISPLAY 0.617021 (-4650 4400);
PAINT SKYBLUE (-4650 4400);
FORCEPROP 1 LAST PACK_TYPE 0603V
J 0
(-4650 4250);
DISPLAY 0.617021 (-4650 4250);
PAINT SKYBLUE (-4650 4250);
FORCEPROP 1 LAST VOLTAGE 4V
J 0
(-4650 4450);
DISPLAY 0.617021 (-4650 4450);
PAINT SKYBLUE (-4650 4450);
FORCEPROP 1 LAST MATERIAL X6S
J 0
(-4650 4350);
DISPLAY 0.617021 (-4650 4350);
PAINT SKYBLUE (-4650 4350);
FORCEPROP 1 LASTPIN (-4700 4550) $PN 1
J 0
(-4690 4530);
DISPLAY 0.617021 (-4690 4530);
PAINT GREEN (-4690 4530);
FORCEPROP 1 LASTPIN (-4700 4350) $PN 2
J 0
(-4690 4330);
DISPLAY 0.617021 (-4690 4330);
PAINT GREEN (-4690 4330);
FORCEPROP 2 LAST CDS_LOCATION C5D29
J 0
(-4650 4550);
DISPLAY 0.617021 (-4650 4550);
PAINT AQUA (-4650 4550);
DISPLAY INVISIBLE (-4650 4550);
FORCEPROP 2 LAST BOM_COST PROC_SOCKET
J 0
(-4650 4650);
DISPLAY 1.021277 (-4650 4650);
PAINT ORANGE (-4650 4650);
DISPLAY INVISIBLE (-4650 4650);
FORCEPROP 2 LAST CDS_LIB dev_discrete
J 0
(-4700 4450);
PAINT ORANGE (-4700 4450);
DISPLAY INVISIBLE (-4700 4450);
FORCEPROP 2 LAST CDS_SEC 1
J 0
(-4650 4650);
PAINT MONO (-4650 4650);
DISPLAY INVISIBLE (-4650 4650);
FORCEPROP 2 LAST $SEC 1
J 0
(-4650 4650);
PAINT MONO (-4650 4650);
DISPLAY INVISIBLE (-4650 4650);
FORCEPROP 1 LAST PATH I102
J 0
(-4650 4600);
DISPLAY 0.978723 (-4650 4600);
PAINT WHITE (-4650 4600);
DISPLAY INVISIBLE (-4650 4600);
FORCEPROP 2 LAST ROOM PVCCIN_CPU0_DECAP_VR
J 0
(-4650 4600);
DISPLAY 1.021277 (-4650 4600);
PAINT ORANGE (-4650 4600);
DISPLAY INVISIBLE (-4650 4600);
FORCEADD CAP_A..1
(-5000 4475);
FORCEPROP 1 LAST LOCATION C5D32
J 0
(-4950 4575);
DISPLAY 0.617021 (-4950 4575);
PAINT AQUA (-4950 4575);
FORCEPROP 1 LAST PART_NUMBER E15431-004
J 0
(-4950 4325);
DISPLAY 0.617021 (-4950 4325);
PAINT BLUE (-4950 4325);
FORCEPROP 1 LAST VALUE 22.0UF
J 0
(-4950 4525);
DISPLAY 0.617021 (-4950 4525);
PAINT SKYBLUE (-4950 4525);
FORCEPROP 1 LAST TOLERANCE 20%
J 0
(-4950 4425);
DISPLAY 0.617021 (-4950 4425);
PAINT SKYBLUE (-4950 4425);
FORCEPROP 1 LAST PACK_TYPE 0603V
J 0
(-4950 4275);
DISPLAY 0.617021 (-4950 4275);
PAINT SKYBLUE (-4950 4275);
FORCEPROP 1 LAST VOLTAGE 4V
J 0
(-4950 4475);
DISPLAY 0.617021 (-4950 4475);
PAINT SKYBLUE (-4950 4475);
FORCEPROP 1 LAST MATERIAL X6S
J 0
(-4950 4375);
DISPLAY 0.617021 (-4950 4375);
PAINT SKYBLUE (-4950 4375);
FORCEPROP 1 LASTPIN (-5000 4575) $PN 1
J 0
(-4990 4555);
DISPLAY 0.617021 (-4990 4555);
PAINT GREEN (-4990 4555);
FORCEPROP 1 LASTPIN (-5000 4375) $PN 2
J 0
(-4990 4355);
DISPLAY 0.617021 (-4990 4355);
PAINT GREEN (-4990 4355);
FORCEPROP 2 LAST CDS_LOCATION C5D32
J 0
(-4950 4575);
DISPLAY 0.617021 (-4950 4575);
PAINT AQUA (-4950 4575);
DISPLAY INVISIBLE (-4950 4575);
FORCEPROP 2 LAST BOM_COST PROC_SOCKET
J 0
(-4950 4675);
DISPLAY 1.021277 (-4950 4675);
PAINT ORANGE (-4950 4675);
DISPLAY INVISIBLE (-4950 4675);
FORCEPROP 2 LAST CDS_LIB dev_discrete
J 0
(-5000 4475);
PAINT ORANGE (-5000 4475);
DISPLAY INVISIBLE (-5000 4475);
FORCEPROP 2 LAST CDS_SEC 1
J 0
(-4950 4675);
PAINT MONO (-4950 4675);
DISPLAY INVISIBLE (-4950 4675);
FORCEPROP 2 LAST $SEC 1
J 0
(-4950 4675);
PAINT MONO (-4950 4675);
DISPLAY INVISIBLE (-4950 4675);
FORCEPROP 1 LAST PATH I103
J 0
(-4950 4625);
DISPLAY 0.978723 (-4950 4625);
PAINT WHITE (-4950 4625);
DISPLAY INVISIBLE (-4950 4625);
FORCEPROP 2 LAST ROOM PVCCIN_CPU0_DECAP_VR
J 0
(-4950 4625);
DISPLAY 1.021277 (-4950 4625);
PAINT ORANGE (-4950 4625);
DISPLAY INVISIBLE (-4950 4625);
FORCEADD CAP_A..1
(-5325 4475);
FORCEPROP 1 LAST LOCATION C5D47
J 0
(-5275 4575);
DISPLAY 0.617021 (-5275 4575);
PAINT AQUA (-5275 4575);
FORCEPROP 1 LAST PART_NUMBER E15431-004
J 0
(-5275 4325);
DISPLAY 0.617021 (-5275 4325);
PAINT BLUE (-5275 4325);
FORCEPROP 1 LAST VALUE 22.0UF
J 0
(-5275 4525);
DISPLAY 0.617021 (-5275 4525);
PAINT SKYBLUE (-5275 4525);
FORCEPROP 1 LAST TOLERANCE 20%
J 0
(-5275 4425);
DISPLAY 0.617021 (-5275 4425);
PAINT SKYBLUE (-5275 4425);
FORCEPROP 1 LAST PACK_TYPE 0603V
J 0
(-5275 4275);
DISPLAY 0.617021 (-5275 4275);
PAINT SKYBLUE (-5275 4275);
FORCEPROP 1 LAST VOLTAGE 4V
J 0
(-5275 4475);
DISPLAY 0.617021 (-5275 4475);
PAINT SKYBLUE (-5275 4475);
FORCEPROP 1 LAST MATERIAL X6S
J 0
(-5275 4375);
DISPLAY 0.617021 (-5275 4375);
PAINT SKYBLUE (-5275 4375);
FORCEPROP 1 LASTPIN (-5325 4575) $PN 1
J 0
(-5315 4555);
DISPLAY 0.617021 (-5315 4555);
PAINT GREEN (-5315 4555);
FORCEPROP 1 LASTPIN (-5325 4375) $PN 2
J 0
(-5315 4355);
DISPLAY 0.617021 (-5315 4355);
PAINT GREEN (-5315 4355);
FORCEPROP 2 LAST CDS_LOCATION C5D47
J 0
(-5275 4575);
DISPLAY 0.617021 (-5275 4575);
PAINT AQUA (-5275 4575);
DISPLAY INVISIBLE (-5275 4575);
FORCEPROP 2 LAST BOM_COST PROC_SOCKET
J 0
(-5275 4675);
DISPLAY 1.021277 (-5275 4675);
PAINT ORANGE (-5275 4675);
DISPLAY INVISIBLE (-5275 4675);
FORCEPROP 2 LAST CDS_LIB dev_discrete
J 0
(-5325 4475);
PAINT ORANGE (-5325 4475);
DISPLAY INVISIBLE (-5325 4475);
FORCEPROP 2 LAST CDS_SEC 1
J 0
(-5275 4675);
PAINT MONO (-5275 4675);
DISPLAY INVISIBLE (-5275 4675);
FORCEPROP 2 LAST $SEC 1
J 0
(-5275 4675);
PAINT MONO (-5275 4675);
DISPLAY INVISIBLE (-5275 4675);
FORCEPROP 1 LAST PATH I104
J 0
(-5275 4625);
DISPLAY 0.978723 (-5275 4625);
PAINT WHITE (-5275 4625);
DISPLAY INVISIBLE (-5275 4625);
FORCEPROP 2 LAST ROOM PVCCIN_CPU0_DECAP_VR
J 0
(-5275 4625);
DISPLAY 1.021277 (-5275 4625);
PAINT ORANGE (-5275 4625);
DISPLAY INVISIBLE (-5275 4625);
FORCEADD GND..1
(-4450 4150);
FORCEPROP 3 LASTPIN (-4450 4200) SIG_NAME GND\g
J 0
(-4440 4210);
DISPLAY 0.659574 (-4440 4210);
PAINT MONO (-4440 4210);
DISPLAY INVISIBLE (-4440 4210);
FORCEPROP 1 LAST VOLTAGE 0
J 0
(-4450 4150);
PAINT SKYBLUE (-4450 4150);
DISPLAY INVISIBLE (-4450 4150);
FORCEPROP 1 LAST SIZE 1B
J 0
(-4375 4100);
DISPLAY 0.893617 (-4375 4100);
PAINT GREEN (-4375 4100);
DISPLAY INVISIBLE (-4375 4100);
FORCEPROP 2 LAST CDS_LIB mstr_symbols
J 0
(-4450 4150);
PAINT ORANGE (-4450 4150);
DISPLAY INVISIBLE (-4450 4150);
FORCEPROP 1 LAST BODY_TYPE PLUMBING
J 0
(-4495 4107);
DISPLAY 0.340426 (-4495 4107);
PAINT GREEN (-4495 4107);
DISPLAY INVISIBLE (-4495 4107);
FORCEPROP 1 LAST PATH I105
J 0
(-4375 4150);
DISPLAY 0.872340 (-4375 4150);
PAINT AQUA (-4375 4150);
DISPLAY INVISIBLE (-4375 4150);
FORCEPROP 1 LAST HDL_POWER GND
J 0
(-4450 4300);
DISPLAY 0.893617 (-4450 4300);
PAINT GREEN (-4450 4300);
DISPLAY INVISIBLE (-4450 4300);
FORCEADD CAP_A..1
(-5000 3775);
FORCEPROP 1 LAST LOCATION C5D31
J 0
(-4950 3875);
DISPLAY 0.617021 (-4950 3875);
PAINT AQUA (-4950 3875);
FORCEPROP 1 LAST PART_NUMBER E15431-004
J 0
(-4950 3625);
DISPLAY 0.617021 (-4950 3625);
PAINT BLUE (-4950 3625);
FORCEPROP 1 LAST VALUE 22.0UF
J 0
(-4950 3825);
DISPLAY 0.617021 (-4950 3825);
PAINT SKYBLUE (-4950 3825);
FORCEPROP 1 LAST TOLERANCE 20%
J 0
(-4950 3725);
DISPLAY 0.617021 (-4950 3725);
PAINT SKYBLUE (-4950 3725);
FORCEPROP 1 LAST PACK_TYPE 0603V
J 0
(-4950 3575);
DISPLAY 0.617021 (-4950 3575);
PAINT SKYBLUE (-4950 3575);
FORCEPROP 1 LAST VOLTAGE 4V
J 0
(-4950 3775);
DISPLAY 0.617021 (-4950 3775);
PAINT SKYBLUE (-4950 3775);
FORCEPROP 1 LAST MATERIAL X6S
J 0
(-4950 3675);
DISPLAY 0.617021 (-4950 3675);
PAINT SKYBLUE (-4950 3675);
FORCEPROP 1 LASTPIN (-5000 3875) $PN 1
J 0
(-4990 3855);
DISPLAY 0.617021 (-4990 3855);
PAINT GREEN (-4990 3855);
FORCEPROP 1 LASTPIN (-5000 3675) $PN 2
J 0
(-4990 3655);
DISPLAY 0.617021 (-4990 3655);
PAINT GREEN (-4990 3655);
FORCEPROP 2 LAST CDS_LOCATION C5D31
J 0
(-4950 3875);
DISPLAY 0.617021 (-4950 3875);
PAINT AQUA (-4950 3875);
DISPLAY INVISIBLE (-4950 3875);
FORCEPROP 2 LAST BOM_COST PROC_SOCKET
J 0
(-4950 3975);
DISPLAY 1.021277 (-4950 3975);
PAINT ORANGE (-4950 3975);
DISPLAY INVISIBLE (-4950 3975);
FORCEPROP 2 LAST CDS_LIB dev_discrete
J 0
(-5000 3775);
PAINT ORANGE (-5000 3775);
DISPLAY INVISIBLE (-5000 3775);
FORCEPROP 2 LAST CDS_SEC 1
J 0
(-4950 3975);
PAINT MONO (-4950 3975);
DISPLAY INVISIBLE (-4950 3975);
FORCEPROP 2 LAST $SEC 1
J 0
(-4950 3975);
PAINT MONO (-4950 3975);
DISPLAY INVISIBLE (-4950 3975);
FORCEPROP 1 LAST PATH I106
J 0
(-4950 3925);
DISPLAY 0.978723 (-4950 3925);
PAINT WHITE (-4950 3925);
DISPLAY INVISIBLE (-4950 3925);
FORCEPROP 2 LAST ROOM PVCCIN_CPU0_DECAP_VR
J 0
(-4950 3925);
DISPLAY 1.021277 (-4950 3925);
PAINT ORANGE (-4950 3925);
DISPLAY INVISIBLE (-4950 3925);
FORCEADD CAP_A..1
(-5325 3800);
FORCEPROP 1 LAST LOCATION C5D46
J 0
(-5275 3900);
DISPLAY 0.617021 (-5275 3900);
PAINT AQUA (-5275 3900);
FORCEPROP 1 LAST PART_NUMBER E15431-004
J 0
(-5275 3650);
DISPLAY 0.617021 (-5275 3650);
PAINT BLUE (-5275 3650);
FORCEPROP 1 LAST VALUE 22.0UF
J 0
(-5275 3850);
DISPLAY 0.617021 (-5275 3850);
PAINT SKYBLUE (-5275 3850);
FORCEPROP 1 LAST TOLERANCE 20%
J 0
(-5275 3750);
DISPLAY 0.617021 (-5275 3750);
PAINT SKYBLUE (-5275 3750);
FORCEPROP 1 LAST PACK_TYPE 0603V
J 0
(-5275 3600);
DISPLAY 0.617021 (-5275 3600);
PAINT SKYBLUE (-5275 3600);
FORCEPROP 1 LAST VOLTAGE 4V
J 0
(-5275 3800);
DISPLAY 0.617021 (-5275 3800);
PAINT SKYBLUE (-5275 3800);
FORCEPROP 1 LAST MATERIAL X6S
J 0
(-5275 3700);
DISPLAY 0.617021 (-5275 3700);
PAINT SKYBLUE (-5275 3700);
FORCEPROP 1 LASTPIN (-5325 3900) $PN 1
J 0
(-5315 3880);
DISPLAY 0.617021 (-5315 3880);
PAINT GREEN (-5315 3880);
FORCEPROP 1 LASTPIN (-5325 3700) $PN 2
J 0
(-5315 3680);
DISPLAY 0.617021 (-5315 3680);
PAINT GREEN (-5315 3680);
FORCEPROP 2 LAST CDS_LOCATION C5D46
J 0
(-5275 3900);
DISPLAY 0.617021 (-5275 3900);
PAINT AQUA (-5275 3900);
DISPLAY INVISIBLE (-5275 3900);
FORCEPROP 2 LAST BOM_COST PROC_SOCKET
J 0
(-5275 4000);
DISPLAY 1.021277 (-5275 4000);
PAINT ORANGE (-5275 4000);
DISPLAY INVISIBLE (-5275 4000);
FORCEPROP 2 LAST CDS_LIB dev_discrete
J 0
(-5325 3800);
PAINT ORANGE (-5325 3800);
DISPLAY INVISIBLE (-5325 3800);
FORCEPROP 2 LAST CDS_SEC 1
J 0
(-5275 4000);
PAINT MONO (-5275 4000);
DISPLAY INVISIBLE (-5275 4000);
FORCEPROP 2 LAST $SEC 1
J 0
(-5275 4000);
PAINT MONO (-5275 4000);
DISPLAY INVISIBLE (-5275 4000);
FORCEPROP 1 LAST PATH I107
J 0
(-5275 3950);
DISPLAY 0.978723 (-5275 3950);
PAINT WHITE (-5275 3950);
DISPLAY INVISIBLE (-5275 3950);
FORCEPROP 2 LAST ROOM PVCCIN_CPU0_DECAP_VR
J 0
(-5275 3950);
DISPLAY 1.021277 (-5275 3950);
PAINT ORANGE (-5275 3950);
DISPLAY INVISIBLE (-5275 3950);
FORCEADD CAP..1
(-4075 3125);
FORCEPROP 1 LAST LOCATION C5D10
J 0
(-4025 3225);
DISPLAY 0.617021 (-4025 3225);
PAINT AQUA (-4025 3225);
FORCEPROP 1 LAST PART_NUMBER E15431-001
J 0
(-4025 2975);
DISPLAY 0.617021 (-4025 2975);
PAINT BLUE (-4025 2975);
FORCEPROP 1 LAST VALUE 10UF
J 0
(-4025 3175);
DISPLAY 0.617021 (-4025 3175);
PAINT SKYBLUE (-4025 3175);
FORCEPROP 1 LAST TOLERANCE 20%
J 0
(-4025 3075);
DISPLAY 0.617021 (-4025 3075);
PAINT SKYBLUE (-4025 3075);
FORCEPROP 1 LAST PACK_TYPE 0603LF
J 0
(-4025 2925);
DISPLAY 0.617021 (-4025 2925);
PAINT SKYBLUE (-4025 2925);
FORCEPROP 1 LAST VOLTAGE 4V
J 0
(-4025 3125);
DISPLAY 0.617021 (-4025 3125);
PAINT SKYBLUE (-4025 3125);
FORCEPROP 1 LAST MATERIAL X6S
J 0
(-4025 3025);
DISPLAY 0.617021 (-4025 3025);
PAINT SKYBLUE (-4025 3025);
FORCEPROP 1 LASTPIN (-4075 3025) $PN 2
J 0
(-4065 3005);
DISPLAY 0.617021 (-4065 3005);
PAINT GREEN (-4065 3005);
FORCEPROP 1 LASTPIN (-4075 3225) $PN 1
J 0
(-4065 3205);
DISPLAY 0.617021 (-4065 3205);
PAINT GREEN (-4065 3205);
FORCEPROP 2 LAST BOM_COST PROC_SOCKET
J 0
(-4025 3325);
DISPLAY 1.021277 (-4025 3325);
PAINT ORANGE (-4025 3325);
DISPLAY INVISIBLE (-4025 3325);
FORCEPROP 2 LAST CDS_LIB mstr_discrete
J 0
(-4075 3125);
PAINT ORANGE (-4075 3125);
DISPLAY INVISIBLE (-4075 3125);
FORCEPROP 2 LAST CDS_SEC 1
J 0
(-4025 3325);
PAINT MONO (-4025 3325);
DISPLAY INVISIBLE (-4025 3325);
FORCEPROP 2 LAST $SEC 1
J 0
(-4025 3325);
PAINT MONO (-4025 3325);
DISPLAY INVISIBLE (-4025 3325);
FORCEPROP 2 LAST CDS_LOCATION C5D10
J 0
(-4025 3225);
DISPLAY 0.617021 (-4025 3225);
PAINT AQUA (-4025 3225);
DISPLAY INVISIBLE (-4025 3225);
FORCEPROP 1 LAST PATH I108
J 0
(-4025 3275);
DISPLAY 0.978723 (-4025 3275);
PAINT WHITE (-4025 3275);
DISPLAY INVISIBLE (-4025 3275);
FORCEPROP 2 LAST ROOM PVCCIN_CPU0_DECAP_VR
J 0
(-4025 3275);
DISPLAY 1.021277 (-4025 3275);
PAINT ORANGE (-4025 3275);
DISPLAY INVISIBLE (-4025 3275);
FORCEADD CAP_A..1
(-4750 3175);
FORCEPROP 1 LAST LOCATION C5D27
J 0
(-4700 3275);
DISPLAY 0.617021 (-4700 3275);
PAINT AQUA (-4700 3275);
FORCEPROP 1 LAST PART_NUMBER E15431-004
J 0
(-4700 3025);
DISPLAY 0.617021 (-4700 3025);
PAINT BLUE (-4700 3025);
FORCEPROP 1 LAST VALUE 22.0UF
J 0
(-4700 3225);
DISPLAY 0.617021 (-4700 3225);
PAINT SKYBLUE (-4700 3225);
FORCEPROP 1 LAST TOLERANCE 20%
J 0
(-4700 3125);
DISPLAY 0.617021 (-4700 3125);
PAINT SKYBLUE (-4700 3125);
FORCEPROP 1 LAST PACK_TYPE 0603V
J 0
(-4700 2975);
DISPLAY 0.617021 (-4700 2975);
PAINT SKYBLUE (-4700 2975);
FORCEPROP 1 LAST VOLTAGE 4V
J 0
(-4700 3175);
DISPLAY 0.617021 (-4700 3175);
PAINT SKYBLUE (-4700 3175);
FORCEPROP 1 LAST MATERIAL X6S
J 0
(-4700 3075);
DISPLAY 0.617021 (-4700 3075);
PAINT SKYBLUE (-4700 3075);
FORCEPROP 1 LASTPIN (-4750 3275) $PN 1
J 0
(-4740 3255);
DISPLAY 0.617021 (-4740 3255);
PAINT GREEN (-4740 3255);
FORCEPROP 1 LASTPIN (-4750 3075) $PN 2
J 0
(-4740 3055);
DISPLAY 0.617021 (-4740 3055);
PAINT GREEN (-4740 3055);
FORCEPROP 2 LAST CDS_LOCATION C5D27
J 0
(-4700 3275);
DISPLAY 0.617021 (-4700 3275);
PAINT AQUA (-4700 3275);
DISPLAY INVISIBLE (-4700 3275);
FORCEPROP 2 LAST BOM_COST PROC_SOCKET
J 0
(-4700 3375);
DISPLAY 1.021277 (-4700 3375);
PAINT ORANGE (-4700 3375);
DISPLAY INVISIBLE (-4700 3375);
FORCEPROP 2 LAST CDS_LIB dev_discrete
J 0
(-4750 3175);
PAINT ORANGE (-4750 3175);
DISPLAY INVISIBLE (-4750 3175);
FORCEPROP 2 LAST CDS_SEC 1
J 0
(-4700 3375);
PAINT MONO (-4700 3375);
DISPLAY INVISIBLE (-4700 3375);
FORCEPROP 2 LAST $SEC 1
J 0
(-4700 3375);
PAINT MONO (-4700 3375);
DISPLAY INVISIBLE (-4700 3375);
FORCEPROP 1 LAST PATH I109
J 0
(-4700 3325);
DISPLAY 0.978723 (-4700 3325);
PAINT WHITE (-4700 3325);
DISPLAY INVISIBLE (-4700 3325);
FORCEPROP 2 LAST ROOM PVCCIN_CPU0_DECAP_VR
J 0
(-4700 3325);
DISPLAY 1.021277 (-4700 3325);
PAINT ORANGE (-4700 3325);
DISPLAY INVISIBLE (-4700 3325);
FORCEADD GND..1
(-4450 2850);
FORCEPROP 3 LASTPIN (-4450 2900) SIG_NAME GND\g
J 0
(-4440 2910);
DISPLAY 0.659574 (-4440 2910);
PAINT MONO (-4440 2910);
DISPLAY INVISIBLE (-4440 2910);
FORCEPROP 1 LAST VOLTAGE 0
J 0
(-4450 2850);
PAINT SKYBLUE (-4450 2850);
DISPLAY INVISIBLE (-4450 2850);
FORCEPROP 1 LAST SIZE 1B
J 0
(-4375 2800);
DISPLAY 0.893617 (-4375 2800);
PAINT GREEN (-4375 2800);
DISPLAY INVISIBLE (-4375 2800);
FORCEPROP 2 LAST CDS_LIB mstr_symbols
J 0
(-4450 2850);
PAINT ORANGE (-4450 2850);
DISPLAY INVISIBLE (-4450 2850);
FORCEPROP 1 LAST BODY_TYPE PLUMBING
J 0
(-4495 2807);
DISPLAY 0.340426 (-4495 2807);
PAINT GREEN (-4495 2807);
DISPLAY INVISIBLE (-4495 2807);
FORCEPROP 1 LAST PATH I110
J 0
(-4375 2850);
DISPLAY 0.872340 (-4375 2850);
PAINT AQUA (-4375 2850);
DISPLAY INVISIBLE (-4375 2850);
FORCEPROP 1 LAST HDL_POWER GND
J 0
(-4450 3000);
DISPLAY 0.893617 (-4450 3000);
PAINT GREEN (-4450 3000);
DISPLAY INVISIBLE (-4450 3000);
FORCEADD CAP_A..1
(-5075 3150);
FORCEPROP 1 LAST LOCATION C5D30
J 0
(-5025 3250);
DISPLAY 0.617021 (-5025 3250);
PAINT AQUA (-5025 3250);
FORCEPROP 1 LAST PART_NUMBER E15431-004
J 0
(-5025 3000);
DISPLAY 0.617021 (-5025 3000);
PAINT BLUE (-5025 3000);
FORCEPROP 1 LAST VALUE 22.0UF
J 0
(-5025 3200);
DISPLAY 0.617021 (-5025 3200);
PAINT SKYBLUE (-5025 3200);
FORCEPROP 1 LAST TOLERANCE 20%
J 0
(-5025 3100);
DISPLAY 0.617021 (-5025 3100);
PAINT SKYBLUE (-5025 3100);
FORCEPROP 1 LAST PACK_TYPE 0603V
J 0
(-5025 2950);
DISPLAY 0.617021 (-5025 2950);
PAINT SKYBLUE (-5025 2950);
FORCEPROP 1 LAST VOLTAGE 4V
J 0
(-5025 3150);
DISPLAY 0.617021 (-5025 3150);
PAINT SKYBLUE (-5025 3150);
FORCEPROP 1 LAST MATERIAL X6S
J 0
(-5025 3050);
DISPLAY 0.617021 (-5025 3050);
PAINT SKYBLUE (-5025 3050);
FORCEPROP 1 LASTPIN (-5075 3250) $PN 1
J 0
(-5065 3230);
DISPLAY 0.617021 (-5065 3230);
PAINT GREEN (-5065 3230);
FORCEPROP 1 LASTPIN (-5075 3050) $PN 2
J 0
(-5065 3030);
DISPLAY 0.617021 (-5065 3030);
PAINT GREEN (-5065 3030);
FORCEPROP 2 LAST CDS_LOCATION C5D30
J 0
(-5025 3250);
DISPLAY 0.617021 (-5025 3250);
PAINT AQUA (-5025 3250);
DISPLAY INVISIBLE (-5025 3250);
FORCEPROP 2 LAST BOM_COST PROC_SOCKET
J 0
(-5025 3350);
DISPLAY 1.021277 (-5025 3350);
PAINT ORANGE (-5025 3350);
DISPLAY INVISIBLE (-5025 3350);
FORCEPROP 2 LAST CDS_LIB dev_discrete
J 0
(-5075 3150);
PAINT ORANGE (-5075 3150);
DISPLAY INVISIBLE (-5075 3150);
FORCEPROP 2 LAST CDS_SEC 1
J 0
(-5025 3350);
PAINT MONO (-5025 3350);
DISPLAY INVISIBLE (-5025 3350);
FORCEPROP 2 LAST $SEC 1
J 0
(-5025 3350);
PAINT MONO (-5025 3350);
DISPLAY INVISIBLE (-5025 3350);
FORCEPROP 1 LAST PATH I111
J 0
(-5025 3300);
DISPLAY 0.978723 (-5025 3300);
PAINT WHITE (-5025 3300);
DISPLAY INVISIBLE (-5025 3300);
FORCEPROP 2 LAST ROOM PVCCIN_CPU0_DECAP_VR
J 0
(-5025 3300);
DISPLAY 1.021277 (-5025 3300);
PAINT ORANGE (-5025 3300);
DISPLAY INVISIBLE (-5025 3300);
FORCEADD CAP_A..1
(-5350 3150);
FORCEPROP 1 LAST LOCATION C5D60
J 0
(-5300 3250);
DISPLAY 0.617021 (-5300 3250);
PAINT AQUA (-5300 3250);
FORCEPROP 1 LAST PART_NUMBER E15431-004
J 0
(-5300 3000);
DISPLAY 0.617021 (-5300 3000);
PAINT BLUE (-5300 3000);
FORCEPROP 1 LAST VALUE 22.0UF
J 0
(-5300 3200);
DISPLAY 0.617021 (-5300 3200);
PAINT SKYBLUE (-5300 3200);
FORCEPROP 1 LAST TOLERANCE 20%
J 0
(-5300 3100);
DISPLAY 0.617021 (-5300 3100);
PAINT SKYBLUE (-5300 3100);
FORCEPROP 1 LAST PACK_TYPE 0603V
J 0
(-5300 2950);
DISPLAY 0.617021 (-5300 2950);
PAINT SKYBLUE (-5300 2950);
FORCEPROP 1 LAST VOLTAGE 4V
J 0
(-5300 3150);
DISPLAY 0.617021 (-5300 3150);
PAINT SKYBLUE (-5300 3150);
FORCEPROP 1 LAST MATERIAL X6S
J 0
(-5300 3050);
DISPLAY 0.617021 (-5300 3050);
PAINT SKYBLUE (-5300 3050);
FORCEPROP 1 LASTPIN (-5350 3250) $PN 1
J 0
(-5340 3230);
DISPLAY 0.617021 (-5340 3230);
PAINT GREEN (-5340 3230);
FORCEPROP 1 LASTPIN (-5350 3050) $PN 2
J 0
(-5340 3030);
DISPLAY 0.617021 (-5340 3030);
PAINT GREEN (-5340 3030);
FORCEPROP 2 LAST CDS_LOCATION C5D60
J 0
(-5300 3250);
DISPLAY 0.617021 (-5300 3250);
PAINT AQUA (-5300 3250);
DISPLAY INVISIBLE (-5300 3250);
FORCEPROP 2 LAST BOM_COST PROC_SOCKET
J 0
(-5300 3350);
DISPLAY 1.021277 (-5300 3350);
PAINT ORANGE (-5300 3350);
DISPLAY INVISIBLE (-5300 3350);
FORCEPROP 2 LAST CDS_LIB dev_discrete
J 0
(-5350 3150);
PAINT ORANGE (-5350 3150);
DISPLAY INVISIBLE (-5350 3150);
FORCEPROP 2 LAST CDS_SEC 1
J 0
(-5300 3350);
PAINT MONO (-5300 3350);
DISPLAY INVISIBLE (-5300 3350);
FORCEPROP 2 LAST $SEC 1
J 0
(-5300 3350);
PAINT MONO (-5300 3350);
DISPLAY INVISIBLE (-5300 3350);
FORCEPROP 1 LAST PATH I112
J 0
(-5300 3300);
DISPLAY 0.978723 (-5300 3300);
PAINT WHITE (-5300 3300);
DISPLAY INVISIBLE (-5300 3300);
FORCEPROP 2 LAST ROOM PVCCIN_CPU0_DECAP_VR
J 0
(-5300 3300);
DISPLAY 1.021277 (-5300 3300);
PAINT ORANGE (-5300 3300);
DISPLAY INVISIBLE (-5300 3300);
FORCEADD CAP_A..1
(-5625 3175);
FORCEPROP 1 LAST LOCATION C5D61
J 0
(-5575 3275);
DISPLAY 0.617021 (-5575 3275);
PAINT AQUA (-5575 3275);
FORCEPROP 1 LAST PART_NUMBER E15431-004
J 0
(-5575 3025);
DISPLAY 0.617021 (-5575 3025);
PAINT BLUE (-5575 3025);
FORCEPROP 1 LAST VALUE 22.0UF
J 0
(-5575 3225);
DISPLAY 0.617021 (-5575 3225);
PAINT SKYBLUE (-5575 3225);
FORCEPROP 1 LAST TOLERANCE 20%
J 0
(-5575 3125);
DISPLAY 0.617021 (-5575 3125);
PAINT SKYBLUE (-5575 3125);
FORCEPROP 1 LAST PACK_TYPE 0603V
J 0
(-5575 2975);
DISPLAY 0.617021 (-5575 2975);
PAINT SKYBLUE (-5575 2975);
FORCEPROP 1 LAST VOLTAGE 4V
J 0
(-5575 3175);
DISPLAY 0.617021 (-5575 3175);
PAINT SKYBLUE (-5575 3175);
FORCEPROP 1 LAST MATERIAL X6S
J 0
(-5575 3075);
DISPLAY 0.617021 (-5575 3075);
PAINT SKYBLUE (-5575 3075);
FORCEPROP 1 LASTPIN (-5625 3275) $PN 1
J 0
(-5615 3255);
DISPLAY 0.617021 (-5615 3255);
PAINT GREEN (-5615 3255);
FORCEPROP 1 LASTPIN (-5625 3075) $PN 2
J 0
(-5615 3055);
DISPLAY 0.617021 (-5615 3055);
PAINT GREEN (-5615 3055);
FORCEPROP 2 LAST CDS_LOCATION C5D61
J 0
(-5575 3275);
DISPLAY 0.617021 (-5575 3275);
PAINT AQUA (-5575 3275);
DISPLAY INVISIBLE (-5575 3275);
FORCEPROP 2 LAST BOM_COST PROC_SOCKET
J 0
(-5575 3375);
DISPLAY 1.021277 (-5575 3375);
PAINT ORANGE (-5575 3375);
DISPLAY INVISIBLE (-5575 3375);
FORCEPROP 2 LAST CDS_LIB dev_discrete
J 0
(-5625 3175);
PAINT ORANGE (-5625 3175);
DISPLAY INVISIBLE (-5625 3175);
FORCEPROP 2 LAST CDS_SEC 1
J 0
(-5575 3375);
PAINT MONO (-5575 3375);
DISPLAY INVISIBLE (-5575 3375);
FORCEPROP 2 LAST $SEC 1
J 0
(-5575 3375);
PAINT MONO (-5575 3375);
DISPLAY INVISIBLE (-5575 3375);
FORCEPROP 1 LAST PATH I113
J 0
(-5575 3325);
DISPLAY 0.978723 (-5575 3325);
PAINT WHITE (-5575 3325);
DISPLAY INVISIBLE (-5575 3325);
FORCEPROP 2 LAST ROOM PVCCIN_CPU0_DECAP_VR
J 0
(-5575 3325);
DISPLAY 1.021277 (-5575 3325);
PAINT ORANGE (-5575 3325);
DISPLAY INVISIBLE (-5575 3325);
FORCEADD CAP_A..1
(-5625 3800);
FORCEPROP 1 LAST LOCATION C5D41
J 0
(-5575 3900);
DISPLAY 0.617021 (-5575 3900);
PAINT AQUA (-5575 3900);
FORCEPROP 1 LAST PART_NUMBER E15431-004
J 0
(-5575 3650);
DISPLAY 0.617021 (-5575 3650);
PAINT BLUE (-5575 3650);
FORCEPROP 1 LAST VALUE 22.0UF
J 0
(-5575 3850);
DISPLAY 0.617021 (-5575 3850);
PAINT SKYBLUE (-5575 3850);
FORCEPROP 1 LAST TOLERANCE 20%
J 0
(-5575 3750);
DISPLAY 0.617021 (-5575 3750);
PAINT SKYBLUE (-5575 3750);
FORCEPROP 1 LAST PACK_TYPE 0603V
J 0
(-5575 3600);
DISPLAY 0.617021 (-5575 3600);
PAINT SKYBLUE (-5575 3600);
FORCEPROP 1 LAST VOLTAGE 4V
J 0
(-5575 3800);
DISPLAY 0.617021 (-5575 3800);
PAINT SKYBLUE (-5575 3800);
FORCEPROP 1 LAST MATERIAL X6S
J 0
(-5575 3700);
DISPLAY 0.617021 (-5575 3700);
PAINT SKYBLUE (-5575 3700);
FORCEPROP 1 LASTPIN (-5625 3900) $PN 1
J 0
(-5615 3880);
DISPLAY 0.617021 (-5615 3880);
PAINT GREEN (-5615 3880);
FORCEPROP 1 LASTPIN (-5625 3700) $PN 2
J 0
(-5615 3680);
DISPLAY 0.617021 (-5615 3680);
PAINT GREEN (-5615 3680);
FORCEPROP 2 LAST CDS_LOCATION C5D41
J 0
(-5575 3900);
DISPLAY 0.617021 (-5575 3900);
PAINT AQUA (-5575 3900);
DISPLAY INVISIBLE (-5575 3900);
FORCEPROP 2 LAST BOM_COST PROC_SOCKET
J 0
(-5575 4000);
DISPLAY 1.021277 (-5575 4000);
PAINT ORANGE (-5575 4000);
DISPLAY INVISIBLE (-5575 4000);
FORCEPROP 2 LAST CDS_LIB dev_discrete
J 0
(-5625 3800);
PAINT ORANGE (-5625 3800);
DISPLAY INVISIBLE (-5625 3800);
FORCEPROP 2 LAST CDS_SEC 1
J 0
(-5575 4000);
PAINT MONO (-5575 4000);
DISPLAY INVISIBLE (-5575 4000);
FORCEPROP 2 LAST $SEC 1
J 0
(-5575 4000);
PAINT MONO (-5575 4000);
DISPLAY INVISIBLE (-5575 4000);
FORCEPROP 1 LAST PATH I114
J 0
(-5575 3950);
DISPLAY 0.978723 (-5575 3950);
PAINT WHITE (-5575 3950);
DISPLAY INVISIBLE (-5575 3950);
FORCEPROP 2 LAST ROOM PVCCIN_CPU0_DECAP_VR
J 0
(-5575 3950);
DISPLAY 1.021277 (-5575 3950);
PAINT ORANGE (-5575 3950);
DISPLAY INVISIBLE (-5575 3950);
FORCEADD CAP_A..1
(-5625 4475);
FORCEPROP 1 LAST LOCATION C5D40
J 0
(-5575 4575);
DISPLAY 0.617021 (-5575 4575);
PAINT AQUA (-5575 4575);
FORCEPROP 1 LAST PART_NUMBER E15431-004
J 0
(-5575 4325);
DISPLAY 0.617021 (-5575 4325);
PAINT BLUE (-5575 4325);
FORCEPROP 1 LAST VALUE 22.0UF
J 0
(-5575 4525);
DISPLAY 0.617021 (-5575 4525);
PAINT SKYBLUE (-5575 4525);
FORCEPROP 1 LAST TOLERANCE 20%
J 0
(-5575 4425);
DISPLAY 0.617021 (-5575 4425);
PAINT SKYBLUE (-5575 4425);
FORCEPROP 1 LAST PACK_TYPE 0603V
J 0
(-5575 4275);
DISPLAY 0.617021 (-5575 4275);
PAINT SKYBLUE (-5575 4275);
FORCEPROP 1 LAST VOLTAGE 4V
J 0
(-5575 4475);
DISPLAY 0.617021 (-5575 4475);
PAINT SKYBLUE (-5575 4475);
FORCEPROP 1 LAST MATERIAL X6S
J 0
(-5575 4375);
DISPLAY 0.617021 (-5575 4375);
PAINT SKYBLUE (-5575 4375);
FORCEPROP 1 LASTPIN (-5625 4575) $PN 1
J 0
(-5615 4555);
DISPLAY 0.617021 (-5615 4555);
PAINT GREEN (-5615 4555);
FORCEPROP 1 LASTPIN (-5625 4375) $PN 2
J 0
(-5615 4355);
DISPLAY 0.617021 (-5615 4355);
PAINT GREEN (-5615 4355);
FORCEPROP 2 LAST CDS_LOCATION C5D40
J 0
(-5575 4575);
DISPLAY 0.617021 (-5575 4575);
PAINT AQUA (-5575 4575);
DISPLAY INVISIBLE (-5575 4575);
FORCEPROP 2 LAST BOM_COST PROC_SOCKET
J 0
(-5575 4675);
DISPLAY 1.021277 (-5575 4675);
PAINT ORANGE (-5575 4675);
DISPLAY INVISIBLE (-5575 4675);
FORCEPROP 2 LAST CDS_LIB dev_discrete
J 0
(-5625 4475);
PAINT ORANGE (-5625 4475);
DISPLAY INVISIBLE (-5625 4475);
FORCEPROP 2 LAST CDS_SEC 1
J 0
(-5575 4675);
PAINT MONO (-5575 4675);
DISPLAY INVISIBLE (-5575 4675);
FORCEPROP 2 LAST $SEC 1
J 0
(-5575 4675);
PAINT MONO (-5575 4675);
DISPLAY INVISIBLE (-5575 4675);
FORCEPROP 1 LAST PATH I115
J 0
(-5575 4625);
DISPLAY 0.978723 (-5575 4625);
PAINT WHITE (-5575 4625);
DISPLAY INVISIBLE (-5575 4625);
FORCEPROP 2 LAST ROOM PVCCIN_CPU0_DECAP_VR
J 0
(-5575 4625);
DISPLAY 1.021277 (-5575 4625);
PAINT ORANGE (-5575 4625);
DISPLAY INVISIBLE (-5575 4625);
FORCEADD PVCCIN_CPU0..1
(-5950 4750);
FORCEPROP 3 LASTPIN (-5950 4700) SIG_NAME PVCCIN_CPU0\g
J 0
(-5940 4710);
DISPLAY 0.659574 (-5940 4710);
PAINT MONO (-5940 4710);
DISPLAY INVISIBLE (-5940 4710);
FORCEPROP 1 LAST VOLTAGE 2.0V
J 0
(-5995 4707);
DISPLAY 0.340426 (-5995 4707);
PAINT SKYBLUE (-5995 4707);
DISPLAY INVISIBLE (-5995 4707);
FORCEPROP 2 LAST CDS_LIB mstr_symbols
J 0
(-5950 4750);
PAINT ORANGE (-5950 4750);
DISPLAY INVISIBLE (-5950 4750);
FORCEPROP 1 LAST BODY_TYPE PLUMBING
J 0
(-5995 4707);
DISPLAY 0.340426 (-5995 4707);
PAINT GREEN (-5995 4707);
DISPLAY INVISIBLE (-5995 4707);
FORCEPROP 1 LAST PATH I116
J 0
(-5900 4775);
DISPLAY 0.872340 (-5900 4775);
PAINT AQUA (-5900 4775);
DISPLAY INVISIBLE (-5900 4775);
FORCEPROP 1 LAST HDL_POWER PVCCIN_CPU0
J 1
(-5950 4800);
DISPLAY 0.872340 (-5950 4800);
PAINT GREEN (-5950 4800);
DISPLAY INVISIBLE (-5950 4800);
FORCEADD CAP_A..1
(-5950 4475);
FORCEPROP 1 LAST LOCATION C5D14
J 0
(-5900 4575);
DISPLAY 0.617021 (-5900 4575);
PAINT AQUA (-5900 4575);
FORCEPROP 1 LAST PART_NUMBER E15431-004
J 0
(-5900 4325);
DISPLAY 0.617021 (-5900 4325);
PAINT BLUE (-5900 4325);
FORCEPROP 1 LAST VALUE 22.0UF
J 0
(-5900 4525);
DISPLAY 0.617021 (-5900 4525);
PAINT SKYBLUE (-5900 4525);
FORCEPROP 1 LAST TOLERANCE 20%
J 0
(-5900 4425);
DISPLAY 0.617021 (-5900 4425);
PAINT SKYBLUE (-5900 4425);
FORCEPROP 1 LAST PACK_TYPE 0603V
J 0
(-5900 4275);
DISPLAY 0.617021 (-5900 4275);
PAINT SKYBLUE (-5900 4275);
FORCEPROP 1 LAST VOLTAGE 4V
J 0
(-5900 4475);
DISPLAY 0.617021 (-5900 4475);
PAINT SKYBLUE (-5900 4475);
FORCEPROP 1 LAST MATERIAL X6S
J 0
(-5900 4375);
DISPLAY 0.617021 (-5900 4375);
PAINT SKYBLUE (-5900 4375);
FORCEPROP 1 LASTPIN (-5950 4575) $PN 1
J 0
(-5940 4555);
DISPLAY 0.617021 (-5940 4555);
PAINT GREEN (-5940 4555);
FORCEPROP 1 LASTPIN (-5950 4375) $PN 2
J 0
(-5940 4355);
DISPLAY 0.617021 (-5940 4355);
PAINT GREEN (-5940 4355);
FORCEPROP 2 LAST CDS_LOCATION C5D14
J 0
(-5900 4575);
DISPLAY 0.617021 (-5900 4575);
PAINT AQUA (-5900 4575);
DISPLAY INVISIBLE (-5900 4575);
FORCEPROP 2 LAST BOM_COST PROC_SOCKET
J 0
(-5900 4675);
DISPLAY 1.021277 (-5900 4675);
PAINT ORANGE (-5900 4675);
DISPLAY INVISIBLE (-5900 4675);
FORCEPROP 2 LAST CDS_LIB dev_discrete
J 0
(-5950 4475);
PAINT ORANGE (-5950 4475);
DISPLAY INVISIBLE (-5950 4475);
FORCEPROP 2 LAST CDS_SEC 1
J 0
(-5900 4675);
PAINT MONO (-5900 4675);
DISPLAY INVISIBLE (-5900 4675);
FORCEPROP 2 LAST $SEC 1
J 0
(-5900 4675);
PAINT MONO (-5900 4675);
DISPLAY INVISIBLE (-5900 4675);
FORCEPROP 1 LAST PATH I117
J 0
(-5900 4625);
DISPLAY 0.978723 (-5900 4625);
PAINT WHITE (-5900 4625);
DISPLAY INVISIBLE (-5900 4625);
FORCEPROP 2 LAST ROOM PVCCIN_CPU0_DECAP_VR
J 0
(-5900 4625);
DISPLAY 1.021277 (-5900 4625);
PAINT ORANGE (-5900 4625);
DISPLAY INVISIBLE (-5900 4625);
FORCEADD CAP_A..1
(-6350 4475);
FORCEPROP 1 LAST LOCATION C5D17
J 0
(-6300 4575);
DISPLAY 0.617021 (-6300 4575);
PAINT AQUA (-6300 4575);
FORCEPROP 1 LAST PART_NUMBER E15431-004
J 0
(-6300 4325);
DISPLAY 0.617021 (-6300 4325);
PAINT BLUE (-6300 4325);
FORCEPROP 1 LAST VALUE 22.0UF
J 0
(-6300 4525);
DISPLAY 0.617021 (-6300 4525);
PAINT SKYBLUE (-6300 4525);
FORCEPROP 1 LAST TOLERANCE 20%
J 0
(-6300 4425);
DISPLAY 0.617021 (-6300 4425);
PAINT SKYBLUE (-6300 4425);
FORCEPROP 1 LAST PACK_TYPE 0603V
J 0
(-6300 4275);
DISPLAY 0.617021 (-6300 4275);
PAINT SKYBLUE (-6300 4275);
FORCEPROP 1 LAST VOLTAGE 4V
J 0
(-6300 4475);
DISPLAY 0.617021 (-6300 4475);
PAINT SKYBLUE (-6300 4475);
FORCEPROP 1 LAST MATERIAL X6S
J 0
(-6300 4375);
DISPLAY 0.617021 (-6300 4375);
PAINT SKYBLUE (-6300 4375);
FORCEPROP 1 LASTPIN (-6350 4575) $PN 1
J 0
(-6340 4555);
DISPLAY 0.617021 (-6340 4555);
PAINT GREEN (-6340 4555);
FORCEPROP 1 LASTPIN (-6350 4375) $PN 2
J 0
(-6340 4355);
DISPLAY 0.617021 (-6340 4355);
PAINT GREEN (-6340 4355);
FORCEPROP 2 LAST CDS_LOCATION C5D17
J 0
(-6300 4575);
DISPLAY 0.617021 (-6300 4575);
PAINT AQUA (-6300 4575);
DISPLAY INVISIBLE (-6300 4575);
FORCEPROP 2 LAST BOM_COST PROC_SOCKET
J 0
(-6300 4675);
DISPLAY 1.021277 (-6300 4675);
PAINT ORANGE (-6300 4675);
DISPLAY INVISIBLE (-6300 4675);
FORCEPROP 2 LAST CDS_LIB dev_discrete
J 0
(-6350 4475);
PAINT ORANGE (-6350 4475);
DISPLAY INVISIBLE (-6350 4475);
FORCEPROP 2 LAST CDS_SEC 1
J 0
(-6300 4675);
PAINT MONO (-6300 4675);
DISPLAY INVISIBLE (-6300 4675);
FORCEPROP 2 LAST $SEC 1
J 0
(-6300 4675);
PAINT MONO (-6300 4675);
DISPLAY INVISIBLE (-6300 4675);
FORCEPROP 1 LAST PATH I118
J 0
(-6300 4625);
DISPLAY 0.978723 (-6300 4625);
PAINT WHITE (-6300 4625);
DISPLAY INVISIBLE (-6300 4625);
FORCEPROP 2 LAST ROOM PVCCIN_CPU0_DECAP_VR
J 0
(-6300 4625);
DISPLAY 1.021277 (-6300 4625);
PAINT ORANGE (-6300 4625);
DISPLAY INVISIBLE (-6300 4625);
FORCEADD PVCCIN_CPU0..1
(-5925 4075);
FORCEPROP 3 LASTPIN (-5925 4025) SIG_NAME PVCCIN_CPU0\g
J 0
(-5915 4035);
DISPLAY 0.659574 (-5915 4035);
PAINT MONO (-5915 4035);
DISPLAY INVISIBLE (-5915 4035);
FORCEPROP 1 LAST VOLTAGE 2.0V
J 0
(-5970 4032);
DISPLAY 0.340426 (-5970 4032);
PAINT SKYBLUE (-5970 4032);
DISPLAY INVISIBLE (-5970 4032);
FORCEPROP 2 LAST CDS_LIB mstr_symbols
J 0
(-5925 4075);
PAINT ORANGE (-5925 4075);
DISPLAY INVISIBLE (-5925 4075);
FORCEPROP 1 LAST BODY_TYPE PLUMBING
J 0
(-5970 4032);
DISPLAY 0.340426 (-5970 4032);
PAINT GREEN (-5970 4032);
DISPLAY INVISIBLE (-5970 4032);
FORCEPROP 1 LAST PATH I119
J 0
(-5875 4100);
DISPLAY 0.872340 (-5875 4100);
PAINT AQUA (-5875 4100);
DISPLAY INVISIBLE (-5875 4100);
FORCEPROP 1 LAST HDL_POWER PVCCIN_CPU0
J 1
(-5925 4125);
DISPLAY 0.872340 (-5925 4125);
PAINT GREEN (-5925 4125);
DISPLAY INVISIBLE (-5925 4125);
FORCEADD CAP..1
(-2850 950);
FORCEPROP 1 LAST LOCATION C4P9
J 0
(-2800 1050);
DISPLAY 0.617021 (-2800 1050);
PAINT AQUA (-2800 1050);
FORCEPROP 1 LAST PART_NUMBER C95333-006
R 1
J 0
(-2900 775);
DISPLAY 0.617021 (-2900 775);
PAINT BLUE (-2900 775);
FORCEPROP 1 LAST VALUE 47UF
J 0
(-2800 1000);
DISPLAY 0.617021 (-2800 1000);
PAINT SKYBLUE (-2800 1000);
FORCEPROP 1 LAST TOLERANCE 20%
J 0
(-2800 900);
DISPLAY 0.617021 (-2800 900);
PAINT SKYBLUE (-2800 900);
FORCEPROP 1 LAST PACK_TYPE 0805
J 0
(-2800 800);
DISPLAY 0.617021 (-2800 800);
PAINT SKYBLUE (-2800 800);
FORCEPROP 1 LASTPIN (-2850 850) $PN 2
J 0
(-2840 830);
DISPLAY 0.617021 (-2840 830);
PAINT ORANGE (-2840 830);
FORCEPROP 1 LASTPIN (-2850 1050) $PN 1
J 0
(-2840 1030);
DISPLAY 0.617021 (-2840 1030);
PAINT ORANGE (-2840 1030);
FORCEPROP 1 LAST VOLTAGE 4V
J 0
(-2800 950);
PAINT SKYBLUE (-2800 950);
DISPLAY INVISIBLE (-2800 950);
FORCEPROP 1 LAST MATERIAL X6S
J 0
(-2800 850);
PAINT SKYBLUE (-2800 850);
DISPLAY INVISIBLE (-2800 850);
FORCEPROP 2 LAST BOM_COST PROC_SOCKET
J 0
(-2800 1150);
DISPLAY 1.021277 (-2800 1150);
PAINT ORANGE (-2800 1150);
DISPLAY INVISIBLE (-2800 1150);
FORCEPROP 2 LAST CDS_LIB mstr_discrete
J 0
(-2850 950);
PAINT ORANGE (-2850 950);
DISPLAY INVISIBLE (-2850 950);
FORCEPROP 2 LAST CDS_SEC 1
J 0
(-2790 1170);
PAINT MONO (-2790 1170);
DISPLAY INVISIBLE (-2790 1170);
FORCEPROP 2 LAST $SEC 1
J 0
(-2790 1170);
PAINT MONO (-2790 1170);
DISPLAY INVISIBLE (-2790 1170);
FORCEPROP 2 LAST CDS_LOCATION C4P9
J 0
(-2800 1050);
DISPLAY 0.617021 (-2800 1050);
PAINT AQUA (-2800 1050);
DISPLAY INVISIBLE (-2800 1050);
FORCEPROP 1 LAST PATH I12
J 0
(-2800 1100);
DISPLAY 0.978723 (-2800 1100);
PAINT WHITE (-2800 1100);
DISPLAY INVISIBLE (-2800 1100);
FORCEPROP 2 LAST ROOM PVCCIN_CPU0_DECAP_VR
J 0
(-2800 1100);
DISPLAY 1.021277 (-2800 1100);
PAINT ORANGE (-2800 1100);
DISPLAY INVISIBLE (-2800 1100);
FORCEADD CAP_A..1
(-5925 3800);
FORCEPROP 1 LAST LOCATION C5D58
J 0
(-5875 3900);
DISPLAY 0.617021 (-5875 3900);
PAINT AQUA (-5875 3900);
FORCEPROP 1 LAST PART_NUMBER E15431-004
J 0
(-5875 3650);
DISPLAY 0.617021 (-5875 3650);
PAINT BLUE (-5875 3650);
FORCEPROP 1 LAST VALUE 22.0UF
J 0
(-5875 3850);
DISPLAY 0.617021 (-5875 3850);
PAINT SKYBLUE (-5875 3850);
FORCEPROP 1 LAST TOLERANCE 20%
J 0
(-5875 3750);
DISPLAY 0.617021 (-5875 3750);
PAINT SKYBLUE (-5875 3750);
FORCEPROP 1 LAST PACK_TYPE 0603V
J 0
(-5875 3600);
DISPLAY 0.617021 (-5875 3600);
PAINT SKYBLUE (-5875 3600);
FORCEPROP 1 LAST VOLTAGE 4V
J 0
(-5875 3800);
DISPLAY 0.617021 (-5875 3800);
PAINT SKYBLUE (-5875 3800);
FORCEPROP 1 LAST MATERIAL X6S
J 0
(-5875 3700);
DISPLAY 0.617021 (-5875 3700);
PAINT SKYBLUE (-5875 3700);
FORCEPROP 1 LASTPIN (-5925 3900) $PN 1
J 0
(-5915 3880);
DISPLAY 0.617021 (-5915 3880);
PAINT GREEN (-5915 3880);
FORCEPROP 1 LASTPIN (-5925 3700) $PN 2
J 0
(-5915 3680);
DISPLAY 0.617021 (-5915 3680);
PAINT GREEN (-5915 3680);
FORCEPROP 2 LAST CDS_LOCATION C5D58
J 0
(-5875 3900);
DISPLAY 0.617021 (-5875 3900);
PAINT AQUA (-5875 3900);
DISPLAY INVISIBLE (-5875 3900);
FORCEPROP 2 LAST BOM_COST PROC_SOCKET
J 0
(-5875 4000);
DISPLAY 1.021277 (-5875 4000);
PAINT ORANGE (-5875 4000);
DISPLAY INVISIBLE (-5875 4000);
FORCEPROP 2 LAST CDS_LIB dev_discrete
J 0
(-5925 3800);
PAINT ORANGE (-5925 3800);
DISPLAY INVISIBLE (-5925 3800);
FORCEPROP 2 LAST CDS_SEC 1
J 0
(-5875 4000);
PAINT MONO (-5875 4000);
DISPLAY INVISIBLE (-5875 4000);
FORCEPROP 2 LAST $SEC 1
J 0
(-5875 4000);
PAINT MONO (-5875 4000);
DISPLAY INVISIBLE (-5875 4000);
FORCEPROP 1 LAST PATH I120
J 0
(-5875 3950);
DISPLAY 0.978723 (-5875 3950);
PAINT WHITE (-5875 3950);
DISPLAY INVISIBLE (-5875 3950);
FORCEPROP 2 LAST ROOM PVCCIN_CPU0_DECAP_VR
J 0
(-5875 3950);
DISPLAY 1.021277 (-5875 3950);
PAINT ORANGE (-5875 3950);
DISPLAY INVISIBLE (-5875 3950);
FORCEADD PVCCIN_CPU0..1
(-5900 3450);
FORCEPROP 3 LASTPIN (-5900 3400) SIG_NAME PVCCIN_CPU0\g
J 0
(-5890 3410);
DISPLAY 0.659574 (-5890 3410);
PAINT MONO (-5890 3410);
DISPLAY INVISIBLE (-5890 3410);
FORCEPROP 1 LAST VOLTAGE 2.0V
J 0
(-5945 3407);
DISPLAY 0.340426 (-5945 3407);
PAINT SKYBLUE (-5945 3407);
DISPLAY INVISIBLE (-5945 3407);
FORCEPROP 2 LAST CDS_LIB mstr_symbols
J 0
(-5900 3450);
PAINT ORANGE (-5900 3450);
DISPLAY INVISIBLE (-5900 3450);
FORCEPROP 1 LAST BODY_TYPE PLUMBING
J 0
(-5945 3407);
DISPLAY 0.340426 (-5945 3407);
PAINT GREEN (-5945 3407);
DISPLAY INVISIBLE (-5945 3407);
FORCEPROP 1 LAST PATH I121
J 0
(-5850 3475);
DISPLAY 0.872340 (-5850 3475);
PAINT AQUA (-5850 3475);
DISPLAY INVISIBLE (-5850 3475);
FORCEPROP 1 LAST HDL_POWER PVCCIN_CPU0
J 1
(-5900 3500);
DISPLAY 0.872340 (-5900 3500);
PAINT GREEN (-5900 3500);
DISPLAY INVISIBLE (-5900 3500);
FORCEADD GND..1
(-6350 4150);
FORCEPROP 3 LASTPIN (-6350 4200) SIG_NAME GND\g
J 0
(-6340 4210);
DISPLAY 0.659574 (-6340 4210);
PAINT MONO (-6340 4210);
DISPLAY INVISIBLE (-6340 4210);
FORCEPROP 1 LAST VOLTAGE 0
J 0
(-6350 4150);
PAINT SKYBLUE (-6350 4150);
DISPLAY INVISIBLE (-6350 4150);
FORCEPROP 1 LAST SIZE 1B
J 0
(-6275 4100);
DISPLAY 0.893617 (-6275 4100);
PAINT GREEN (-6275 4100);
DISPLAY INVISIBLE (-6275 4100);
FORCEPROP 2 LAST CDS_LIB mstr_symbols
J 0
(-6350 4150);
PAINT ORANGE (-6350 4150);
DISPLAY INVISIBLE (-6350 4150);
FORCEPROP 1 LAST BODY_TYPE PLUMBING
J 0
(-6395 4107);
DISPLAY 0.340426 (-6395 4107);
PAINT GREEN (-6395 4107);
DISPLAY INVISIBLE (-6395 4107);
FORCEPROP 1 LAST PATH I122
J 0
(-6275 4150);
DISPLAY 0.872340 (-6275 4150);
PAINT AQUA (-6275 4150);
DISPLAY INVISIBLE (-6275 4150);
FORCEPROP 1 LAST HDL_POWER GND
J 0
(-6350 4300);
DISPLAY 0.893617 (-6350 4300);
PAINT GREEN (-6350 4300);
DISPLAY INVISIBLE (-6350 4300);
FORCEADD CAP_A..1
(-6300 3800);
FORCEPROP 1 LAST LOCATION C5D16
J 0
(-6250 3900);
DISPLAY 0.617021 (-6250 3900);
PAINT AQUA (-6250 3900);
FORCEPROP 1 LAST PART_NUMBER E15431-004
J 0
(-6250 3650);
DISPLAY 0.617021 (-6250 3650);
PAINT BLUE (-6250 3650);
FORCEPROP 1 LAST VALUE 22.0UF
J 0
(-6250 3850);
DISPLAY 0.617021 (-6250 3850);
PAINT SKYBLUE (-6250 3850);
FORCEPROP 1 LAST TOLERANCE 20%
J 0
(-6250 3750);
DISPLAY 0.617021 (-6250 3750);
PAINT SKYBLUE (-6250 3750);
FORCEPROP 1 LAST PACK_TYPE 0603V
J 0
(-6250 3600);
DISPLAY 0.617021 (-6250 3600);
PAINT SKYBLUE (-6250 3600);
FORCEPROP 1 LAST VOLTAGE 4V
J 0
(-6250 3800);
DISPLAY 0.617021 (-6250 3800);
PAINT SKYBLUE (-6250 3800);
FORCEPROP 1 LAST MATERIAL X6S
J 0
(-6250 3700);
DISPLAY 0.617021 (-6250 3700);
PAINT SKYBLUE (-6250 3700);
FORCEPROP 1 LASTPIN (-6300 3900) $PN 1
J 0
(-6290 3880);
DISPLAY 0.617021 (-6290 3880);
PAINT GREEN (-6290 3880);
FORCEPROP 1 LASTPIN (-6300 3700) $PN 2
J 0
(-6290 3680);
DISPLAY 0.617021 (-6290 3680);
PAINT GREEN (-6290 3680);
FORCEPROP 2 LAST CDS_LOCATION C5D16
J 0
(-6250 3900);
DISPLAY 0.617021 (-6250 3900);
PAINT AQUA (-6250 3900);
DISPLAY INVISIBLE (-6250 3900);
FORCEPROP 2 LAST BOM_COST PROC_SOCKET
J 0
(-6250 4000);
DISPLAY 1.021277 (-6250 4000);
PAINT ORANGE (-6250 4000);
DISPLAY INVISIBLE (-6250 4000);
FORCEPROP 2 LAST CDS_LIB dev_discrete
J 0
(-6300 3800);
PAINT ORANGE (-6300 3800);
DISPLAY INVISIBLE (-6300 3800);
FORCEPROP 2 LAST CDS_SEC 1
J 0
(-6250 4000);
PAINT MONO (-6250 4000);
DISPLAY INVISIBLE (-6250 4000);
FORCEPROP 2 LAST $SEC 1
J 0
(-6250 4000);
PAINT MONO (-6250 4000);
DISPLAY INVISIBLE (-6250 4000);
FORCEPROP 1 LAST PATH I123
J 0
(-6250 3950);
DISPLAY 0.978723 (-6250 3950);
PAINT WHITE (-6250 3950);
DISPLAY INVISIBLE (-6250 3950);
FORCEPROP 2 LAST ROOM PVCCIN_CPU0_DECAP_VR
J 0
(-6250 3950);
DISPLAY 1.021277 (-6250 3950);
PAINT ORANGE (-6250 3950);
DISPLAY INVISIBLE (-6250 3950);
FORCEADD GND..1
(-6300 3475);
FORCEPROP 3 LASTPIN (-6300 3525) SIG_NAME GND\g
J 0
(-6290 3535);
DISPLAY 0.659574 (-6290 3535);
PAINT MONO (-6290 3535);
DISPLAY INVISIBLE (-6290 3535);
FORCEPROP 1 LAST VOLTAGE 0
J 0
(-6300 3475);
PAINT SKYBLUE (-6300 3475);
DISPLAY INVISIBLE (-6300 3475);
FORCEPROP 1 LAST SIZE 1B
J 0
(-6225 3425);
DISPLAY 0.893617 (-6225 3425);
PAINT GREEN (-6225 3425);
DISPLAY INVISIBLE (-6225 3425);
FORCEPROP 2 LAST CDS_LIB mstr_symbols
J 0
(-6300 3475);
PAINT ORANGE (-6300 3475);
DISPLAY INVISIBLE (-6300 3475);
FORCEPROP 1 LAST BODY_TYPE PLUMBING
J 0
(-6345 3432);
DISPLAY 0.340426 (-6345 3432);
PAINT GREEN (-6345 3432);
DISPLAY INVISIBLE (-6345 3432);
FORCEPROP 1 LAST PATH I124
J 0
(-6225 3475);
DISPLAY 0.872340 (-6225 3475);
PAINT AQUA (-6225 3475);
DISPLAY INVISIBLE (-6225 3475);
FORCEPROP 1 LAST HDL_POWER GND
J 0
(-6300 3625);
DISPLAY 0.893617 (-6300 3625);
PAINT GREEN (-6300 3625);
DISPLAY INVISIBLE (-6300 3625);
FORCEADD CAP_A..1
(-6675 4475);
FORCEPROP 1 LAST LOCATION C5D5
J 0
(-6625 4575);
DISPLAY 0.617021 (-6625 4575);
PAINT AQUA (-6625 4575);
FORCEPROP 1 LAST PART_NUMBER E15431-004
J 0
(-6625 4325);
DISPLAY 0.617021 (-6625 4325);
PAINT BLUE (-6625 4325);
FORCEPROP 1 LAST VALUE 22.0UF
J 0
(-6625 4525);
DISPLAY 0.617021 (-6625 4525);
PAINT SKYBLUE (-6625 4525);
FORCEPROP 1 LAST TOLERANCE 20%
J 0
(-6625 4425);
DISPLAY 0.617021 (-6625 4425);
PAINT SKYBLUE (-6625 4425);
FORCEPROP 1 LAST PACK_TYPE 0603V
J 0
(-6625 4275);
DISPLAY 0.617021 (-6625 4275);
PAINT SKYBLUE (-6625 4275);
FORCEPROP 1 LAST VOLTAGE 4V
J 0
(-6625 4475);
DISPLAY 0.617021 (-6625 4475);
PAINT SKYBLUE (-6625 4475);
FORCEPROP 1 LAST MATERIAL X6S
J 0
(-6625 4375);
DISPLAY 0.617021 (-6625 4375);
PAINT SKYBLUE (-6625 4375);
FORCEPROP 1 LASTPIN (-6675 4575) $PN 1
J 0
(-6665 4555);
DISPLAY 0.617021 (-6665 4555);
PAINT GREEN (-6665 4555);
FORCEPROP 1 LASTPIN (-6675 4375) $PN 2
J 0
(-6665 4355);
DISPLAY 0.617021 (-6665 4355);
PAINT GREEN (-6665 4355);
FORCEPROP 2 LAST CDS_LOCATION C5D5
J 0
(-6625 4575);
DISPLAY 0.617021 (-6625 4575);
PAINT AQUA (-6625 4575);
DISPLAY INVISIBLE (-6625 4575);
FORCEPROP 2 LAST BOM_COST PROC_SOCKET
J 0
(-6625 4675);
DISPLAY 1.021277 (-6625 4675);
PAINT ORANGE (-6625 4675);
DISPLAY INVISIBLE (-6625 4675);
FORCEPROP 2 LAST CDS_LIB dev_discrete
J 0
(-6675 4475);
PAINT ORANGE (-6675 4475);
DISPLAY INVISIBLE (-6675 4475);
FORCEPROP 2 LAST CDS_SEC 1
J 0
(-6625 4675);
PAINT MONO (-6625 4675);
DISPLAY INVISIBLE (-6625 4675);
FORCEPROP 2 LAST $SEC 1
J 0
(-6625 4675);
PAINT MONO (-6625 4675);
DISPLAY INVISIBLE (-6625 4675);
FORCEPROP 1 LAST PATH I125
J 0
(-6625 4625);
DISPLAY 0.978723 (-6625 4625);
PAINT WHITE (-6625 4625);
DISPLAY INVISIBLE (-6625 4625);
FORCEPROP 2 LAST ROOM PVCCIN_CPU0_DECAP_VR
J 0
(-6625 4625);
DISPLAY 1.021277 (-6625 4625);
PAINT ORANGE (-6625 4625);
DISPLAY INVISIBLE (-6625 4625);
FORCEADD CAP_A..1
(-7050 4475);
FORCEPROP 1 LAST LOCATION C5D1
J 0
(-7000 4575);
DISPLAY 0.617021 (-7000 4575);
PAINT AQUA (-7000 4575);
FORCEPROP 1 LAST PART_NUMBER E15431-004
J 0
(-7000 4325);
DISPLAY 0.617021 (-7000 4325);
PAINT BLUE (-7000 4325);
FORCEPROP 1 LAST VALUE 22.0UF
J 0
(-7000 4525);
DISPLAY 0.617021 (-7000 4525);
PAINT SKYBLUE (-7000 4525);
FORCEPROP 1 LAST TOLERANCE 20%
J 0
(-7000 4425);
DISPLAY 0.617021 (-7000 4425);
PAINT SKYBLUE (-7000 4425);
FORCEPROP 1 LAST PACK_TYPE 0603V
J 0
(-7000 4275);
DISPLAY 0.617021 (-7000 4275);
PAINT SKYBLUE (-7000 4275);
FORCEPROP 1 LAST VOLTAGE 4V
J 0
(-7000 4475);
DISPLAY 0.617021 (-7000 4475);
PAINT SKYBLUE (-7000 4475);
FORCEPROP 1 LAST MATERIAL X6S
J 0
(-7000 4375);
DISPLAY 0.617021 (-7000 4375);
PAINT SKYBLUE (-7000 4375);
FORCEPROP 1 LASTPIN (-7050 4575) $PN 1
J 0
(-7040 4555);
DISPLAY 0.617021 (-7040 4555);
PAINT GREEN (-7040 4555);
FORCEPROP 1 LASTPIN (-7050 4375) $PN 2
J 0
(-7040 4355);
DISPLAY 0.617021 (-7040 4355);
PAINT GREEN (-7040 4355);
FORCEPROP 2 LAST CDS_LOCATION C5D1
J 0
(-7000 4575);
DISPLAY 0.617021 (-7000 4575);
PAINT AQUA (-7000 4575);
DISPLAY INVISIBLE (-7000 4575);
FORCEPROP 2 LAST BOM_COST PROC_SOCKET
J 0
(-7000 4675);
DISPLAY 1.021277 (-7000 4675);
PAINT ORANGE (-7000 4675);
DISPLAY INVISIBLE (-7000 4675);
FORCEPROP 2 LAST CDS_LIB dev_discrete
J 0
(-7050 4475);
PAINT ORANGE (-7050 4475);
DISPLAY INVISIBLE (-7050 4475);
FORCEPROP 2 LAST CDS_SEC 1
J 0
(-7000 4675);
PAINT MONO (-7000 4675);
DISPLAY INVISIBLE (-7000 4675);
FORCEPROP 2 LAST $SEC 1
J 0
(-7000 4675);
PAINT MONO (-7000 4675);
DISPLAY INVISIBLE (-7000 4675);
FORCEPROP 1 LAST PATH I126
J 0
(-7000 4625);
DISPLAY 0.978723 (-7000 4625);
PAINT WHITE (-7000 4625);
DISPLAY INVISIBLE (-7000 4625);
FORCEPROP 2 LAST ROOM PVCCIN_CPU0_DECAP_VR
J 0
(-7000 4625);
DISPLAY 1.021277 (-7000 4625);
PAINT ORANGE (-7000 4625);
DISPLAY INVISIBLE (-7000 4625);
FORCEADD CAP_A..1
(-7375 4475);
FORCEPROP 1 LAST LOCATION C5D4
J 0
(-7325 4575);
DISPLAY 0.617021 (-7325 4575);
PAINT AQUA (-7325 4575);
FORCEPROP 1 LAST PART_NUMBER E15431-004
J 0
(-7325 4325);
DISPLAY 0.617021 (-7325 4325);
PAINT BLUE (-7325 4325);
FORCEPROP 1 LAST VALUE 22.0UF
J 0
(-7325 4525);
DISPLAY 0.617021 (-7325 4525);
PAINT SKYBLUE (-7325 4525);
FORCEPROP 1 LAST TOLERANCE 20%
J 0
(-7325 4425);
DISPLAY 0.617021 (-7325 4425);
PAINT SKYBLUE (-7325 4425);
FORCEPROP 1 LAST PACK_TYPE 0603V
J 0
(-7325 4275);
DISPLAY 0.617021 (-7325 4275);
PAINT SKYBLUE (-7325 4275);
FORCEPROP 1 LAST VOLTAGE 4V
J 0
(-7325 4475);
DISPLAY 0.617021 (-7325 4475);
PAINT SKYBLUE (-7325 4475);
FORCEPROP 1 LAST MATERIAL X6S
J 0
(-7325 4375);
DISPLAY 0.617021 (-7325 4375);
PAINT SKYBLUE (-7325 4375);
FORCEPROP 1 LASTPIN (-7375 4575) $PN 1
J 0
(-7365 4555);
DISPLAY 0.617021 (-7365 4555);
PAINT GREEN (-7365 4555);
FORCEPROP 1 LASTPIN (-7375 4375) $PN 2
J 0
(-7365 4355);
DISPLAY 0.617021 (-7365 4355);
PAINT GREEN (-7365 4355);
FORCEPROP 2 LAST CDS_LOCATION C5D4
J 0
(-7325 4575);
DISPLAY 0.617021 (-7325 4575);
PAINT AQUA (-7325 4575);
DISPLAY INVISIBLE (-7325 4575);
FORCEPROP 2 LAST BOM_COST PROC_SOCKET
J 0
(-7325 4675);
DISPLAY 1.021277 (-7325 4675);
PAINT ORANGE (-7325 4675);
DISPLAY INVISIBLE (-7325 4675);
FORCEPROP 2 LAST CDS_LIB dev_discrete
J 0
(-7375 4475);
PAINT ORANGE (-7375 4475);
DISPLAY INVISIBLE (-7375 4475);
FORCEPROP 2 LAST CDS_SEC 1
J 0
(-7325 4675);
PAINT MONO (-7325 4675);
DISPLAY INVISIBLE (-7325 4675);
FORCEPROP 2 LAST $SEC 1
J 0
(-7325 4675);
PAINT MONO (-7325 4675);
DISPLAY INVISIBLE (-7325 4675);
FORCEPROP 1 LAST PATH I127
J 0
(-7325 4625);
DISPLAY 0.978723 (-7325 4625);
PAINT WHITE (-7325 4625);
DISPLAY INVISIBLE (-7325 4625);
FORCEPROP 2 LAST ROOM PVCCIN_CPU0_DECAP_VR
J 0
(-7325 4625);
DISPLAY 1.021277 (-7325 4625);
PAINT ORANGE (-7325 4625);
DISPLAY INVISIBLE (-7325 4625);
FORCEADD CAP_A..1
(-6650 3800);
FORCEPROP 1 LAST LOCATION C5D19
J 0
(-6600 3900);
DISPLAY 0.617021 (-6600 3900);
PAINT AQUA (-6600 3900);
FORCEPROP 1 LAST PART_NUMBER E15431-004
J 0
(-6600 3650);
DISPLAY 0.617021 (-6600 3650);
PAINT BLUE (-6600 3650);
FORCEPROP 1 LAST VALUE 22.0UF
J 0
(-6600 3850);
DISPLAY 0.617021 (-6600 3850);
PAINT SKYBLUE (-6600 3850);
FORCEPROP 1 LAST TOLERANCE 20%
J 0
(-6600 3750);
DISPLAY 0.617021 (-6600 3750);
PAINT SKYBLUE (-6600 3750);
FORCEPROP 1 LAST PACK_TYPE 0603V
J 0
(-6600 3600);
DISPLAY 0.617021 (-6600 3600);
PAINT SKYBLUE (-6600 3600);
FORCEPROP 1 LAST VOLTAGE 4V
J 0
(-6600 3800);
DISPLAY 0.617021 (-6600 3800);
PAINT SKYBLUE (-6600 3800);
FORCEPROP 1 LAST MATERIAL X6S
J 0
(-6600 3700);
DISPLAY 0.617021 (-6600 3700);
PAINT SKYBLUE (-6600 3700);
FORCEPROP 1 LASTPIN (-6650 3900) $PN 1
J 0
(-6640 3880);
DISPLAY 0.617021 (-6640 3880);
PAINT GREEN (-6640 3880);
FORCEPROP 1 LASTPIN (-6650 3700) $PN 2
J 0
(-6640 3680);
DISPLAY 0.617021 (-6640 3680);
PAINT GREEN (-6640 3680);
FORCEPROP 2 LAST CDS_LOCATION C5D19
J 0
(-6600 3900);
DISPLAY 0.617021 (-6600 3900);
PAINT AQUA (-6600 3900);
DISPLAY INVISIBLE (-6600 3900);
FORCEPROP 2 LAST BOM_COST PROC_SOCKET
J 0
(-6600 4000);
DISPLAY 1.021277 (-6600 4000);
PAINT ORANGE (-6600 4000);
DISPLAY INVISIBLE (-6600 4000);
FORCEPROP 2 LAST CDS_LIB dev_discrete
J 0
(-6650 3800);
PAINT ORANGE (-6650 3800);
DISPLAY INVISIBLE (-6650 3800);
FORCEPROP 2 LAST CDS_SEC 1
J 0
(-6600 4000);
PAINT MONO (-6600 4000);
DISPLAY INVISIBLE (-6600 4000);
FORCEPROP 2 LAST $SEC 1
J 0
(-6600 4000);
PAINT MONO (-6600 4000);
DISPLAY INVISIBLE (-6600 4000);
FORCEPROP 1 LAST PATH I128
J 0
(-6600 3950);
DISPLAY 0.978723 (-6600 3950);
PAINT WHITE (-6600 3950);
DISPLAY INVISIBLE (-6600 3950);
FORCEPROP 2 LAST ROOM PVCCIN_CPU0_DECAP_VR
J 0
(-6600 3950);
DISPLAY 1.021277 (-6600 3950);
PAINT ORANGE (-6600 3950);
DISPLAY INVISIBLE (-6600 3950);
FORCEADD CAP_A..1
(-7000 3800);
FORCEPROP 1 LAST LOCATION C5D59
J 0
(-6950 3900);
DISPLAY 0.617021 (-6950 3900);
PAINT AQUA (-6950 3900);
FORCEPROP 1 LAST PART_NUMBER E15431-004
J 0
(-6950 3650);
DISPLAY 0.617021 (-6950 3650);
PAINT BLUE (-6950 3650);
FORCEPROP 1 LAST VALUE 22.0UF
J 0
(-6950 3850);
DISPLAY 0.617021 (-6950 3850);
PAINT SKYBLUE (-6950 3850);
FORCEPROP 1 LAST TOLERANCE 20%
J 0
(-6950 3750);
DISPLAY 0.617021 (-6950 3750);
PAINT SKYBLUE (-6950 3750);
FORCEPROP 1 LAST PACK_TYPE 0603V
J 0
(-6950 3600);
DISPLAY 0.617021 (-6950 3600);
PAINT SKYBLUE (-6950 3600);
FORCEPROP 1 LAST VOLTAGE 4V
J 0
(-6950 3800);
DISPLAY 0.617021 (-6950 3800);
PAINT SKYBLUE (-6950 3800);
FORCEPROP 1 LAST MATERIAL X6S
J 0
(-6950 3700);
DISPLAY 0.617021 (-6950 3700);
PAINT SKYBLUE (-6950 3700);
FORCEPROP 1 LASTPIN (-7000 3900) $PN 1
J 0
(-6990 3880);
DISPLAY 0.617021 (-6990 3880);
PAINT GREEN (-6990 3880);
FORCEPROP 1 LASTPIN (-7000 3700) $PN 2
J 0
(-6990 3680);
DISPLAY 0.617021 (-6990 3680);
PAINT GREEN (-6990 3680);
FORCEPROP 2 LAST CDS_LOCATION C5D59
J 0
(-6950 3900);
DISPLAY 0.617021 (-6950 3900);
PAINT AQUA (-6950 3900);
DISPLAY INVISIBLE (-6950 3900);
FORCEPROP 2 LAST BOM_COST PROC_SOCKET
J 0
(-6950 4000);
DISPLAY 1.021277 (-6950 4000);
PAINT ORANGE (-6950 4000);
DISPLAY INVISIBLE (-6950 4000);
FORCEPROP 2 LAST CDS_LIB dev_discrete
J 0
(-7000 3800);
PAINT ORANGE (-7000 3800);
DISPLAY INVISIBLE (-7000 3800);
FORCEPROP 2 LAST CDS_SEC 1
J 0
(-6950 4000);
PAINT MONO (-6950 4000);
DISPLAY INVISIBLE (-6950 4000);
FORCEPROP 2 LAST $SEC 1
J 0
(-6950 4000);
PAINT MONO (-6950 4000);
DISPLAY INVISIBLE (-6950 4000);
FORCEPROP 1 LAST PATH I129
J 0
(-6950 3950);
DISPLAY 0.978723 (-6950 3950);
PAINT WHITE (-6950 3950);
DISPLAY INVISIBLE (-6950 3950);
FORCEPROP 2 LAST ROOM PVCCIN_CPU0_DECAP_VR
J 0
(-6950 3950);
DISPLAY 1.021277 (-6950 3950);
PAINT ORANGE (-6950 3950);
DISPLAY INVISIBLE (-6950 3950);
FORCEADD CAP..1
(-3825 2175);
FORCEPROP 1 LAST LOCATION C5P19
J 0
(-3775 2275);
DISPLAY 0.617021 (-3775 2275);
PAINT AQUA (-3775 2275);
FORCEPROP 1 LAST PART_NUMBER C95333-006
R 1
J 0
(-3875 2000);
DISPLAY 0.617021 (-3875 2000);
PAINT BLUE (-3875 2000);
FORCEPROP 1 LAST VALUE 47UF
J 0
(-3775 2225);
DISPLAY 0.617021 (-3775 2225);
PAINT SKYBLUE (-3775 2225);
FORCEPROP 1 LAST TOLERANCE 20%
J 0
(-3775 2125);
DISPLAY 0.617021 (-3775 2125);
PAINT SKYBLUE (-3775 2125);
FORCEPROP 1 LAST PACK_TYPE 0805
J 0
(-3775 2025);
DISPLAY 0.617021 (-3775 2025);
PAINT SKYBLUE (-3775 2025);
FORCEPROP 1 LASTPIN (-3825 2075) $PN 2
J 0
(-3815 2055);
DISPLAY 0.617021 (-3815 2055);
PAINT GREEN (-3815 2055);
FORCEPROP 1 LASTPIN (-3825 2275) $PN 1
J 0
(-3815 2255);
DISPLAY 0.617021 (-3815 2255);
PAINT GREEN (-3815 2255);
FORCEPROP 1 LAST VOLTAGE 4V
J 0
(-3775 2175);
PAINT SKYBLUE (-3775 2175);
DISPLAY INVISIBLE (-3775 2175);
FORCEPROP 1 LAST MATERIAL X6S
J 0
(-3775 2075);
PAINT SKYBLUE (-3775 2075);
DISPLAY INVISIBLE (-3775 2075);
FORCEPROP 2 LAST CDS_LIB mstr_discrete
J 0
(-3825 2175);
PAINT ORANGE (-3825 2175);
DISPLAY INVISIBLE (-3825 2175);
FORCEPROP 2 LAST BOM_COST PROC_SOCKET
J 0
(-3775 2375);
DISPLAY 1.021277 (-3775 2375);
PAINT ORANGE (-3775 2375);
DISPLAY INVISIBLE (-3775 2375);
FORCEPROP 2 LAST CDS_SEC 1
J 0
(-3775 2375);
DISPLAY 1.021277 (-3775 2375);
PAINT ORANGE (-3775 2375);
DISPLAY INVISIBLE (-3775 2375);
FORCEPROP 2 LAST $SEC 1
J 0
(-3775 2375);
DISPLAY 0.680851 (-3775 2375);
PAINT MONO (-3775 2375);
DISPLAY INVISIBLE (-3775 2375);
FORCEPROP 2 LAST CDS_LOCATION C5P19
J 0
(-3775 2275);
DISPLAY 0.617021 (-3775 2275);
PAINT AQUA (-3775 2275);
DISPLAY INVISIBLE (-3775 2275);
FORCEPROP 1 LAST PATH I13
J 0
(-3775 2325);
DISPLAY 0.978723 (-3775 2325);
PAINT WHITE (-3775 2325);
DISPLAY INVISIBLE (-3775 2325);
FORCEPROP 2 LAST ROOM PVCCIN_CPU0_DECAP_VR
J 0
(-3775 2325);
DISPLAY 1.021277 (-3775 2325);
PAINT ORANGE (-3775 2325);
DISPLAY INVISIBLE (-3775 2325);
FORCEADD CAP_A..1
(-7325 3800);
FORCEPROP 1 LAST LOCATION C5D3
J 0
(-7275 3900);
DISPLAY 0.617021 (-7275 3900);
PAINT AQUA (-7275 3900);
FORCEPROP 1 LAST PART_NUMBER E15431-004
J 0
(-7275 3650);
DISPLAY 0.617021 (-7275 3650);
PAINT BLUE (-7275 3650);
FORCEPROP 1 LAST VALUE 22.0UF
J 0
(-7275 3850);
DISPLAY 0.617021 (-7275 3850);
PAINT SKYBLUE (-7275 3850);
FORCEPROP 1 LAST TOLERANCE 20%
J 0
(-7275 3750);
DISPLAY 0.617021 (-7275 3750);
PAINT SKYBLUE (-7275 3750);
FORCEPROP 1 LAST PACK_TYPE 0603V
J 0
(-7275 3600);
DISPLAY 0.617021 (-7275 3600);
PAINT SKYBLUE (-7275 3600);
FORCEPROP 1 LAST VOLTAGE 4V
J 0
(-7275 3800);
DISPLAY 0.617021 (-7275 3800);
PAINT SKYBLUE (-7275 3800);
FORCEPROP 1 LAST MATERIAL X6S
J 0
(-7275 3700);
DISPLAY 0.617021 (-7275 3700);
PAINT SKYBLUE (-7275 3700);
FORCEPROP 1 LASTPIN (-7325 3900) $PN 1
J 0
(-7315 3880);
DISPLAY 0.617021 (-7315 3880);
PAINT GREEN (-7315 3880);
FORCEPROP 1 LASTPIN (-7325 3700) $PN 2
J 0
(-7315 3680);
DISPLAY 0.617021 (-7315 3680);
PAINT GREEN (-7315 3680);
FORCEPROP 2 LAST CDS_LOCATION C5D3
J 0
(-7275 3900);
DISPLAY 0.617021 (-7275 3900);
PAINT AQUA (-7275 3900);
DISPLAY INVISIBLE (-7275 3900);
FORCEPROP 2 LAST BOM_COST PROC_SOCKET
J 0
(-7275 4000);
DISPLAY 1.021277 (-7275 4000);
PAINT ORANGE (-7275 4000);
DISPLAY INVISIBLE (-7275 4000);
FORCEPROP 2 LAST CDS_LIB dev_discrete
J 0
(-7325 3800);
PAINT ORANGE (-7325 3800);
DISPLAY INVISIBLE (-7325 3800);
FORCEPROP 2 LAST CDS_SEC 1
J 0
(-7275 4000);
PAINT MONO (-7275 4000);
DISPLAY INVISIBLE (-7275 4000);
FORCEPROP 2 LAST $SEC 1
J 0
(-7275 4000);
PAINT MONO (-7275 4000);
DISPLAY INVISIBLE (-7275 4000);
FORCEPROP 1 LAST PATH I130
J 0
(-7275 3950);
DISPLAY 0.978723 (-7275 3950);
PAINT WHITE (-7275 3950);
DISPLAY INVISIBLE (-7275 3950);
FORCEPROP 2 LAST ROOM PVCCIN_CPU0_DECAP_VR
J 0
(-7275 3950);
DISPLAY 1.021277 (-7275 3950);
PAINT ORANGE (-7275 3950);
DISPLAY INVISIBLE (-7275 3950);
FORCEADD CAP_A..1
(-5900 3150);
FORCEPROP 1 LAST LOCATION C5D43
J 0
(-5850 3250);
DISPLAY 0.617021 (-5850 3250);
PAINT AQUA (-5850 3250);
FORCEPROP 1 LAST PART_NUMBER E15431-004
J 0
(-5850 3000);
DISPLAY 0.617021 (-5850 3000);
PAINT BLUE (-5850 3000);
FORCEPROP 1 LAST VALUE 22.0UF
J 0
(-5850 3200);
DISPLAY 0.617021 (-5850 3200);
PAINT SKYBLUE (-5850 3200);
FORCEPROP 1 LAST TOLERANCE 20%
J 0
(-5850 3100);
DISPLAY 0.617021 (-5850 3100);
PAINT SKYBLUE (-5850 3100);
FORCEPROP 1 LAST PACK_TYPE 0603V
J 0
(-5850 2950);
DISPLAY 0.617021 (-5850 2950);
PAINT SKYBLUE (-5850 2950);
FORCEPROP 1 LAST VOLTAGE 4V
J 0
(-5850 3150);
DISPLAY 0.617021 (-5850 3150);
PAINT SKYBLUE (-5850 3150);
FORCEPROP 1 LAST MATERIAL X6S
J 0
(-5850 3050);
DISPLAY 0.617021 (-5850 3050);
PAINT SKYBLUE (-5850 3050);
FORCEPROP 1 LASTPIN (-5900 3250) $PN 1
J 0
(-5890 3230);
DISPLAY 0.617021 (-5890 3230);
PAINT GREEN (-5890 3230);
FORCEPROP 1 LASTPIN (-5900 3050) $PN 2
J 0
(-5890 3030);
DISPLAY 0.617021 (-5890 3030);
PAINT GREEN (-5890 3030);
FORCEPROP 2 LAST CDS_LOCATION C5D43
J 0
(-5850 3250);
DISPLAY 0.617021 (-5850 3250);
PAINT AQUA (-5850 3250);
DISPLAY INVISIBLE (-5850 3250);
FORCEPROP 2 LAST BOM_COST PROC_SOCKET
J 0
(-5850 3350);
DISPLAY 1.021277 (-5850 3350);
PAINT ORANGE (-5850 3350);
DISPLAY INVISIBLE (-5850 3350);
FORCEPROP 2 LAST CDS_LIB dev_discrete
J 0
(-5900 3150);
PAINT ORANGE (-5900 3150);
DISPLAY INVISIBLE (-5900 3150);
FORCEPROP 2 LAST CDS_SEC 1
J 0
(-5850 3350);
PAINT MONO (-5850 3350);
DISPLAY INVISIBLE (-5850 3350);
FORCEPROP 2 LAST $SEC 1
J 0
(-5850 3350);
PAINT MONO (-5850 3350);
DISPLAY INVISIBLE (-5850 3350);
FORCEPROP 1 LAST PATH I131
J 0
(-5850 3300);
DISPLAY 0.978723 (-5850 3300);
PAINT WHITE (-5850 3300);
DISPLAY INVISIBLE (-5850 3300);
FORCEPROP 2 LAST ROOM PVCCIN_CPU0_DECAP_VR
J 0
(-5850 3300);
DISPLAY 1.021277 (-5850 3300);
PAINT ORANGE (-5850 3300);
DISPLAY INVISIBLE (-5850 3300);
FORCEADD CAP_A..1
(-6250 3175);
FORCEPROP 1 LAST LOCATION C5D15
J 0
(-6200 3275);
DISPLAY 0.617021 (-6200 3275);
PAINT AQUA (-6200 3275);
FORCEPROP 1 LAST PART_NUMBER E15431-004
J 0
(-6200 3025);
DISPLAY 0.617021 (-6200 3025);
PAINT BLUE (-6200 3025);
FORCEPROP 1 LAST VALUE 22.0UF
J 0
(-6200 3225);
DISPLAY 0.617021 (-6200 3225);
PAINT SKYBLUE (-6200 3225);
FORCEPROP 1 LAST TOLERANCE 20%
J 0
(-6200 3125);
DISPLAY 0.617021 (-6200 3125);
PAINT SKYBLUE (-6200 3125);
FORCEPROP 1 LAST PACK_TYPE 0603V
J 0
(-6200 2975);
DISPLAY 0.617021 (-6200 2975);
PAINT SKYBLUE (-6200 2975);
FORCEPROP 1 LAST VOLTAGE 4V
J 0
(-6200 3175);
DISPLAY 0.617021 (-6200 3175);
PAINT SKYBLUE (-6200 3175);
FORCEPROP 1 LAST MATERIAL X6S
J 0
(-6200 3075);
DISPLAY 0.617021 (-6200 3075);
PAINT SKYBLUE (-6200 3075);
FORCEPROP 1 LASTPIN (-6250 3275) $PN 1
J 0
(-6240 3255);
DISPLAY 0.617021 (-6240 3255);
PAINT GREEN (-6240 3255);
FORCEPROP 1 LASTPIN (-6250 3075) $PN 2
J 0
(-6240 3055);
DISPLAY 0.617021 (-6240 3055);
PAINT GREEN (-6240 3055);
FORCEPROP 2 LAST CDS_LOCATION C5D15
J 0
(-6200 3275);
DISPLAY 0.617021 (-6200 3275);
PAINT AQUA (-6200 3275);
DISPLAY INVISIBLE (-6200 3275);
FORCEPROP 2 LAST BOM_COST PROC_SOCKET
J 0
(-6200 3375);
DISPLAY 1.021277 (-6200 3375);
PAINT ORANGE (-6200 3375);
DISPLAY INVISIBLE (-6200 3375);
FORCEPROP 2 LAST CDS_LIB dev_discrete
J 0
(-6250 3175);
PAINT ORANGE (-6250 3175);
DISPLAY INVISIBLE (-6250 3175);
FORCEPROP 2 LAST CDS_SEC 1
J 0
(-6200 3375);
PAINT MONO (-6200 3375);
DISPLAY INVISIBLE (-6200 3375);
FORCEPROP 2 LAST $SEC 1
J 0
(-6200 3375);
PAINT MONO (-6200 3375);
DISPLAY INVISIBLE (-6200 3375);
FORCEPROP 1 LAST PATH I132
J 0
(-6200 3325);
DISPLAY 0.978723 (-6200 3325);
PAINT WHITE (-6200 3325);
DISPLAY INVISIBLE (-6200 3325);
FORCEPROP 2 LAST ROOM PVCCIN_CPU0_DECAP_VR
J 0
(-6200 3325);
DISPLAY 1.021277 (-6200 3325);
PAINT ORANGE (-6200 3325);
DISPLAY INVISIBLE (-6200 3325);
FORCEADD GND..1
(-6250 2850);
FORCEPROP 3 LASTPIN (-6250 2900) SIG_NAME GND\g
J 0
(-6240 2910);
DISPLAY 0.659574 (-6240 2910);
PAINT MONO (-6240 2910);
DISPLAY INVISIBLE (-6240 2910);
FORCEPROP 1 LAST VOLTAGE 0
J 0
(-6250 2850);
PAINT SKYBLUE (-6250 2850);
DISPLAY INVISIBLE (-6250 2850);
FORCEPROP 1 LAST SIZE 1B
J 0
(-6175 2800);
DISPLAY 0.893617 (-6175 2800);
PAINT GREEN (-6175 2800);
DISPLAY INVISIBLE (-6175 2800);
FORCEPROP 2 LAST CDS_LIB mstr_symbols
J 0
(-6250 2850);
PAINT ORANGE (-6250 2850);
DISPLAY INVISIBLE (-6250 2850);
FORCEPROP 1 LAST BODY_TYPE PLUMBING
J 0
(-6295 2807);
DISPLAY 0.340426 (-6295 2807);
PAINT GREEN (-6295 2807);
DISPLAY INVISIBLE (-6295 2807);
FORCEPROP 1 LAST PATH I133
J 0
(-6175 2850);
DISPLAY 0.872340 (-6175 2850);
PAINT AQUA (-6175 2850);
DISPLAY INVISIBLE (-6175 2850);
FORCEPROP 1 LAST HDL_POWER GND
J 0
(-6250 3000);
DISPLAY 0.893617 (-6250 3000);
PAINT GREEN (-6250 3000);
DISPLAY INVISIBLE (-6250 3000);
FORCEADD CAP_A..1
(-6600 3150);
FORCEPROP 1 LAST LOCATION C5D18
J 0
(-6550 3250);
DISPLAY 0.617021 (-6550 3250);
PAINT AQUA (-6550 3250);
FORCEPROP 1 LAST PART_NUMBER E15431-004
J 0
(-6550 3000);
DISPLAY 0.617021 (-6550 3000);
PAINT BLUE (-6550 3000);
FORCEPROP 1 LAST VALUE 22.0UF
J 0
(-6550 3200);
DISPLAY 0.617021 (-6550 3200);
PAINT SKYBLUE (-6550 3200);
FORCEPROP 1 LAST TOLERANCE 20%
J 0
(-6550 3100);
DISPLAY 0.617021 (-6550 3100);
PAINT SKYBLUE (-6550 3100);
FORCEPROP 1 LAST PACK_TYPE 0603V
J 0
(-6550 2950);
DISPLAY 0.617021 (-6550 2950);
PAINT SKYBLUE (-6550 2950);
FORCEPROP 1 LAST VOLTAGE 4V
J 0
(-6550 3150);
DISPLAY 0.617021 (-6550 3150);
PAINT SKYBLUE (-6550 3150);
FORCEPROP 1 LAST MATERIAL X6S
J 0
(-6550 3050);
DISPLAY 0.617021 (-6550 3050);
PAINT SKYBLUE (-6550 3050);
FORCEPROP 1 LASTPIN (-6600 3250) $PN 1
J 0
(-6590 3230);
DISPLAY 0.617021 (-6590 3230);
PAINT GREEN (-6590 3230);
FORCEPROP 1 LASTPIN (-6600 3050) $PN 2
J 0
(-6590 3030);
DISPLAY 0.617021 (-6590 3030);
PAINT GREEN (-6590 3030);
FORCEPROP 2 LAST CDS_LOCATION C5D18
J 0
(-6550 3250);
DISPLAY 0.617021 (-6550 3250);
PAINT AQUA (-6550 3250);
DISPLAY INVISIBLE (-6550 3250);
FORCEPROP 2 LAST BOM_COST PROC_SOCKET
J 0
(-6550 3350);
DISPLAY 1.021277 (-6550 3350);
PAINT ORANGE (-6550 3350);
DISPLAY INVISIBLE (-6550 3350);
FORCEPROP 2 LAST CDS_LIB dev_discrete
J 0
(-6600 3150);
PAINT ORANGE (-6600 3150);
DISPLAY INVISIBLE (-6600 3150);
FORCEPROP 2 LAST CDS_SEC 1
J 0
(-6550 3350);
PAINT MONO (-6550 3350);
DISPLAY INVISIBLE (-6550 3350);
FORCEPROP 2 LAST $SEC 1
J 0
(-6550 3350);
PAINT MONO (-6550 3350);
DISPLAY INVISIBLE (-6550 3350);
FORCEPROP 1 LAST PATH I134
J 0
(-6550 3300);
DISPLAY 0.978723 (-6550 3300);
PAINT WHITE (-6550 3300);
DISPLAY INVISIBLE (-6550 3300);
FORCEPROP 2 LAST ROOM PVCCIN_CPU0_DECAP_VR
J 0
(-6550 3300);
DISPLAY 1.021277 (-6550 3300);
PAINT ORANGE (-6550 3300);
DISPLAY INVISIBLE (-6550 3300);
FORCEADD CAP_A..1
(-6950 3175);
FORCEPROP 1 LAST LOCATION C5D42
J 0
(-6900 3275);
DISPLAY 0.617021 (-6900 3275);
PAINT AQUA (-6900 3275);
FORCEPROP 1 LAST PART_NUMBER E15431-004
J 0
(-6900 3025);
DISPLAY 0.617021 (-6900 3025);
PAINT BLUE (-6900 3025);
FORCEPROP 1 LAST VALUE 22.0UF
J 0
(-6900 3225);
DISPLAY 0.617021 (-6900 3225);
PAINT SKYBLUE (-6900 3225);
FORCEPROP 1 LAST TOLERANCE 20%
J 0
(-6900 3125);
DISPLAY 0.617021 (-6900 3125);
PAINT SKYBLUE (-6900 3125);
FORCEPROP 1 LAST PACK_TYPE 0603V
J 0
(-6900 2975);
DISPLAY 0.617021 (-6900 2975);
PAINT SKYBLUE (-6900 2975);
FORCEPROP 1 LAST VOLTAGE 4V
J 0
(-6900 3175);
DISPLAY 0.617021 (-6900 3175);
PAINT SKYBLUE (-6900 3175);
FORCEPROP 1 LAST MATERIAL X6S
J 0
(-6900 3075);
DISPLAY 0.617021 (-6900 3075);
PAINT SKYBLUE (-6900 3075);
FORCEPROP 1 LASTPIN (-6950 3275) $PN 1
J 0
(-6940 3255);
DISPLAY 0.617021 (-6940 3255);
PAINT GREEN (-6940 3255);
FORCEPROP 1 LASTPIN (-6950 3075) $PN 2
J 0
(-6940 3055);
DISPLAY 0.617021 (-6940 3055);
PAINT GREEN (-6940 3055);
FORCEPROP 2 LAST CDS_LOCATION C5D42
J 0
(-6900 3275);
DISPLAY 0.617021 (-6900 3275);
PAINT AQUA (-6900 3275);
DISPLAY INVISIBLE (-6900 3275);
FORCEPROP 2 LAST BOM_COST PROC_SOCKET
J 0
(-6900 3375);
DISPLAY 1.021277 (-6900 3375);
PAINT ORANGE (-6900 3375);
DISPLAY INVISIBLE (-6900 3375);
FORCEPROP 2 LAST CDS_LIB dev_discrete
J 0
(-6950 3175);
PAINT ORANGE (-6950 3175);
DISPLAY INVISIBLE (-6950 3175);
FORCEPROP 2 LAST CDS_SEC 1
J 0
(-6900 3375);
PAINT MONO (-6900 3375);
DISPLAY INVISIBLE (-6900 3375);
FORCEPROP 2 LAST $SEC 1
J 0
(-6900 3375);
PAINT MONO (-6900 3375);
DISPLAY INVISIBLE (-6900 3375);
FORCEPROP 1 LAST PATH I135
J 0
(-6900 3325);
DISPLAY 0.978723 (-6900 3325);
PAINT WHITE (-6900 3325);
DISPLAY INVISIBLE (-6900 3325);
FORCEPROP 2 LAST ROOM PVCCIN_CPU0_DECAP_VR
J 0
(-6900 3325);
DISPLAY 1.021277 (-6900 3325);
PAINT ORANGE (-6900 3325);
DISPLAY INVISIBLE (-6900 3325);
FORCEADD CAP_A..1
(-7275 3175);
FORCEPROP 1 LAST LOCATION C5D2
J 0
(-7225 3275);
DISPLAY 0.617021 (-7225 3275);
PAINT AQUA (-7225 3275);
FORCEPROP 1 LAST PART_NUMBER E15431-004
J 0
(-7225 3025);
DISPLAY 0.617021 (-7225 3025);
PAINT BLUE (-7225 3025);
FORCEPROP 1 LAST VALUE 22.0UF
J 0
(-7225 3225);
DISPLAY 0.617021 (-7225 3225);
PAINT SKYBLUE (-7225 3225);
FORCEPROP 1 LAST TOLERANCE 20%
J 0
(-7225 3125);
DISPLAY 0.617021 (-7225 3125);
PAINT SKYBLUE (-7225 3125);
FORCEPROP 1 LAST PACK_TYPE 0603V
J 0
(-7225 2975);
DISPLAY 0.617021 (-7225 2975);
PAINT SKYBLUE (-7225 2975);
FORCEPROP 1 LAST VOLTAGE 4V
J 0
(-7225 3175);
DISPLAY 0.617021 (-7225 3175);
PAINT SKYBLUE (-7225 3175);
FORCEPROP 1 LAST MATERIAL X6S
J 0
(-7225 3075);
DISPLAY 0.617021 (-7225 3075);
PAINT SKYBLUE (-7225 3075);
FORCEPROP 1 LASTPIN (-7275 3275) $PN 1
J 0
(-7265 3255);
DISPLAY 0.617021 (-7265 3255);
PAINT GREEN (-7265 3255);
FORCEPROP 1 LASTPIN (-7275 3075) $PN 2
J 0
(-7265 3055);
DISPLAY 0.617021 (-7265 3055);
PAINT GREEN (-7265 3055);
FORCEPROP 2 LAST CDS_LOCATION C5D2
J 0
(-7225 3275);
DISPLAY 0.617021 (-7225 3275);
PAINT AQUA (-7225 3275);
DISPLAY INVISIBLE (-7225 3275);
FORCEPROP 2 LAST BOM_COST PROC_SOCKET
J 0
(-7225 3375);
DISPLAY 1.021277 (-7225 3375);
PAINT ORANGE (-7225 3375);
DISPLAY INVISIBLE (-7225 3375);
FORCEPROP 2 LAST CDS_LIB dev_discrete
J 0
(-7275 3175);
PAINT ORANGE (-7275 3175);
DISPLAY INVISIBLE (-7275 3175);
FORCEPROP 2 LAST CDS_SEC 1
J 0
(-7225 3375);
PAINT MONO (-7225 3375);
DISPLAY INVISIBLE (-7225 3375);
FORCEPROP 2 LAST $SEC 1
J 0
(-7225 3375);
PAINT MONO (-7225 3375);
DISPLAY INVISIBLE (-7225 3375);
FORCEPROP 1 LAST PATH I136
J 0
(-7225 3325);
DISPLAY 0.978723 (-7225 3325);
PAINT WHITE (-7225 3325);
DISPLAY INVISIBLE (-7225 3325);
FORCEPROP 2 LAST ROOM PVCCIN_CPU0_DECAP_VR
J 0
(-7225 3325);
DISPLAY 1.021277 (-7225 3325);
PAINT ORANGE (-7225 3325);
DISPLAY INVISIBLE (-7225 3325);
FORCEADD PVCCIN_CPU0..1
(-7725 4750);
FORCEPROP 3 LASTPIN (-7725 4700) SIG_NAME PVCCIN_CPU0\g
J 0
(-7715 4710);
DISPLAY 0.659574 (-7715 4710);
PAINT MONO (-7715 4710);
DISPLAY INVISIBLE (-7715 4710);
FORCEPROP 1 LAST VOLTAGE 2.0V
J 0
(-7770 4707);
DISPLAY 0.340426 (-7770 4707);
PAINT SKYBLUE (-7770 4707);
DISPLAY INVISIBLE (-7770 4707);
FORCEPROP 2 LAST CDS_LIB mstr_symbols
J 0
(-7725 4750);
PAINT ORANGE (-7725 4750);
DISPLAY INVISIBLE (-7725 4750);
FORCEPROP 1 LAST BODY_TYPE PLUMBING
J 0
(-7770 4707);
DISPLAY 0.340426 (-7770 4707);
PAINT GREEN (-7770 4707);
DISPLAY INVISIBLE (-7770 4707);
FORCEPROP 1 LAST PATH I137
J 0
(-7675 4775);
DISPLAY 0.872340 (-7675 4775);
PAINT AQUA (-7675 4775);
DISPLAY INVISIBLE (-7675 4775);
FORCEPROP 1 LAST HDL_POWER PVCCIN_CPU0
J 1
(-7725 4800);
DISPLAY 0.872340 (-7725 4800);
PAINT GREEN (-7725 4800);
DISPLAY INVISIBLE (-7725 4800);
FORCEADD CAP_A..1
(-7725 4475);
FORCEPROP 1 LAST LOCATION C5D24
J 0
(-7675 4575);
DISPLAY 0.617021 (-7675 4575);
PAINT AQUA (-7675 4575);
FORCEPROP 1 LAST PART_NUMBER E15431-004
J 0
(-7675 4325);
DISPLAY 0.617021 (-7675 4325);
PAINT BLUE (-7675 4325);
FORCEPROP 1 LAST VALUE 22.0UF
J 0
(-7675 4525);
DISPLAY 0.617021 (-7675 4525);
PAINT SKYBLUE (-7675 4525);
FORCEPROP 1 LAST TOLERANCE 20%
J 0
(-7675 4425);
DISPLAY 0.617021 (-7675 4425);
PAINT SKYBLUE (-7675 4425);
FORCEPROP 1 LAST PACK_TYPE 0603V
J 0
(-7675 4275);
DISPLAY 0.617021 (-7675 4275);
PAINT SKYBLUE (-7675 4275);
FORCEPROP 1 LAST VOLTAGE 4V
J 0
(-7675 4475);
DISPLAY 0.617021 (-7675 4475);
PAINT SKYBLUE (-7675 4475);
FORCEPROP 1 LAST MATERIAL X6S
J 0
(-7675 4375);
DISPLAY 0.617021 (-7675 4375);
PAINT SKYBLUE (-7675 4375);
FORCEPROP 1 LASTPIN (-7725 4575) $PN 1
J 0
(-7715 4555);
DISPLAY 0.617021 (-7715 4555);
PAINT GREEN (-7715 4555);
FORCEPROP 1 LASTPIN (-7725 4375) $PN 2
J 0
(-7715 4355);
DISPLAY 0.617021 (-7715 4355);
PAINT GREEN (-7715 4355);
FORCEPROP 2 LAST CDS_LOCATION C5D24
J 0
(-7675 4575);
DISPLAY 0.617021 (-7675 4575);
PAINT AQUA (-7675 4575);
DISPLAY INVISIBLE (-7675 4575);
FORCEPROP 2 LAST BOM_COST PROC_SOCKET
J 0
(-7675 4675);
DISPLAY 1.021277 (-7675 4675);
PAINT ORANGE (-7675 4675);
DISPLAY INVISIBLE (-7675 4675);
FORCEPROP 2 LAST CDS_LIB dev_discrete
J 0
(-7725 4475);
PAINT ORANGE (-7725 4475);
DISPLAY INVISIBLE (-7725 4475);
FORCEPROP 2 LAST CDS_SEC 1
J 0
(-7675 4675);
PAINT MONO (-7675 4675);
DISPLAY INVISIBLE (-7675 4675);
FORCEPROP 2 LAST $SEC 1
J 0
(-7675 4675);
PAINT MONO (-7675 4675);
DISPLAY INVISIBLE (-7675 4675);
FORCEPROP 1 LAST PATH I138
J 0
(-7675 4625);
DISPLAY 0.978723 (-7675 4625);
PAINT WHITE (-7675 4625);
DISPLAY INVISIBLE (-7675 4625);
FORCEPROP 2 LAST ROOM PVCCIN_CPU0_DECAP_VR
J 0
(-7675 4625);
DISPLAY 1.021277 (-7675 4625);
PAINT ORANGE (-7675 4625);
DISPLAY INVISIBLE (-7675 4625);
FORCEADD PVCCIN_CPU0..1
(-7675 4075);
FORCEPROP 3 LASTPIN (-7675 4025) SIG_NAME PVCCIN_CPU0\g
J 0
(-7665 4035);
DISPLAY 0.659574 (-7665 4035);
PAINT MONO (-7665 4035);
DISPLAY INVISIBLE (-7665 4035);
FORCEPROP 1 LAST VOLTAGE 2.0V
J 0
(-7720 4032);
DISPLAY 0.340426 (-7720 4032);
PAINT SKYBLUE (-7720 4032);
DISPLAY INVISIBLE (-7720 4032);
FORCEPROP 2 LAST CDS_LIB mstr_symbols
J 0
(-7675 4075);
PAINT ORANGE (-7675 4075);
DISPLAY INVISIBLE (-7675 4075);
FORCEPROP 1 LAST BODY_TYPE PLUMBING
J 0
(-7720 4032);
DISPLAY 0.340426 (-7720 4032);
PAINT GREEN (-7720 4032);
DISPLAY INVISIBLE (-7720 4032);
FORCEPROP 1 LAST PATH I139
J 0
(-7625 4100);
DISPLAY 0.872340 (-7625 4100);
PAINT AQUA (-7625 4100);
DISPLAY INVISIBLE (-7625 4100);
FORCEPROP 1 LAST HDL_POWER PVCCIN_CPU0
J 1
(-7675 4125);
DISPLAY 0.872340 (-7675 4125);
PAINT GREEN (-7675 4125);
DISPLAY INVISIBLE (-7675 4125);
FORCEADD CAP..1
(-4100 2175);
FORCEPROP 1 LAST LOCATION C4P4
J 0
(-4050 2275);
DISPLAY 0.617021 (-4050 2275);
PAINT AQUA (-4050 2275);
FORCEPROP 1 LAST PART_NUMBER C95333-006
R 1
J 0
(-4150 2000);
DISPLAY 0.617021 (-4150 2000);
PAINT BLUE (-4150 2000);
FORCEPROP 1 LAST VALUE 47UF
J 0
(-4050 2225);
DISPLAY 0.617021 (-4050 2225);
PAINT SKYBLUE (-4050 2225);
FORCEPROP 1 LAST TOLERANCE 20%
J 0
(-4050 2125);
DISPLAY 0.617021 (-4050 2125);
PAINT SKYBLUE (-4050 2125);
FORCEPROP 1 LAST PACK_TYPE 0805
J 0
(-4050 2025);
DISPLAY 0.617021 (-4050 2025);
PAINT SKYBLUE (-4050 2025);
FORCEPROP 1 LASTPIN (-4100 2075) $PN 2
J 0
(-4090 2055);
DISPLAY 0.617021 (-4090 2055);
PAINT GREEN (-4090 2055);
FORCEPROP 1 LASTPIN (-4100 2275) $PN 1
J 0
(-4090 2255);
DISPLAY 0.617021 (-4090 2255);
PAINT GREEN (-4090 2255);
FORCEPROP 1 LAST VOLTAGE 4V
J 0
(-4050 2175);
PAINT SKYBLUE (-4050 2175);
DISPLAY INVISIBLE (-4050 2175);
FORCEPROP 1 LAST MATERIAL X6S
J 0
(-4050 2075);
PAINT SKYBLUE (-4050 2075);
DISPLAY INVISIBLE (-4050 2075);
FORCEPROP 2 LAST CDS_LIB mstr_discrete
J 0
(-4100 2175);
PAINT ORANGE (-4100 2175);
DISPLAY INVISIBLE (-4100 2175);
FORCEPROP 2 LAST BOM_COST PROC_SOCKET
J 0
(-4050 2375);
DISPLAY 1.021277 (-4050 2375);
PAINT ORANGE (-4050 2375);
DISPLAY INVISIBLE (-4050 2375);
FORCEPROP 2 LAST CDS_SEC 1
J 0
(-4050 2375);
DISPLAY 1.021277 (-4050 2375);
PAINT ORANGE (-4050 2375);
DISPLAY INVISIBLE (-4050 2375);
FORCEPROP 2 LAST $SEC 1
J 0
(-4050 2375);
DISPLAY 0.680851 (-4050 2375);
PAINT MONO (-4050 2375);
DISPLAY INVISIBLE (-4050 2375);
FORCEPROP 2 LAST CDS_LOCATION C4P4
J 0
(-4050 2275);
DISPLAY 0.617021 (-4050 2275);
PAINT AQUA (-4050 2275);
DISPLAY INVISIBLE (-4050 2275);
FORCEPROP 1 LAST PATH I14
J 0
(-4050 2325);
DISPLAY 0.978723 (-4050 2325);
PAINT WHITE (-4050 2325);
DISPLAY INVISIBLE (-4050 2325);
FORCEPROP 2 LAST ROOM PVCCIN_CPU0_DECAP_VR
J 0
(-4050 2325);
DISPLAY 1.021277 (-4050 2325);
PAINT ORANGE (-4050 2325);
DISPLAY INVISIBLE (-4050 2325);
FORCEADD CAP_A..1
(-7675 3800);
FORCEPROP 1 LAST LOCATION C5D39
J 0
(-7625 3900);
DISPLAY 0.617021 (-7625 3900);
PAINT AQUA (-7625 3900);
FORCEPROP 1 LAST PART_NUMBER E15431-004
J 0
(-7625 3650);
DISPLAY 0.617021 (-7625 3650);
PAINT BLUE (-7625 3650);
FORCEPROP 1 LAST VALUE 22.0UF
J 0
(-7625 3850);
DISPLAY 0.617021 (-7625 3850);
PAINT SKYBLUE (-7625 3850);
FORCEPROP 1 LAST TOLERANCE 20%
J 0
(-7625 3750);
DISPLAY 0.617021 (-7625 3750);
PAINT SKYBLUE (-7625 3750);
FORCEPROP 1 LAST PACK_TYPE 0603V
J 0
(-7625 3600);
DISPLAY 0.617021 (-7625 3600);
PAINT SKYBLUE (-7625 3600);
FORCEPROP 1 LAST VOLTAGE 4V
J 0
(-7625 3800);
DISPLAY 0.617021 (-7625 3800);
PAINT SKYBLUE (-7625 3800);
FORCEPROP 1 LAST MATERIAL X6S
J 0
(-7625 3700);
DISPLAY 0.617021 (-7625 3700);
PAINT SKYBLUE (-7625 3700);
FORCEPROP 1 LASTPIN (-7675 3900) $PN 1
J 0
(-7665 3880);
DISPLAY 0.617021 (-7665 3880);
PAINT GREEN (-7665 3880);
FORCEPROP 1 LASTPIN (-7675 3700) $PN 2
J 0
(-7665 3680);
DISPLAY 0.617021 (-7665 3680);
PAINT GREEN (-7665 3680);
FORCEPROP 2 LAST CDS_LOCATION C5D39
J 0
(-7625 3900);
DISPLAY 0.617021 (-7625 3900);
PAINT AQUA (-7625 3900);
DISPLAY INVISIBLE (-7625 3900);
FORCEPROP 2 LAST BOM_COST PROC_SOCKET
J 0
(-7625 4000);
DISPLAY 1.021277 (-7625 4000);
PAINT ORANGE (-7625 4000);
DISPLAY INVISIBLE (-7625 4000);
FORCEPROP 2 LAST CDS_LIB dev_discrete
J 0
(-7675 3800);
PAINT ORANGE (-7675 3800);
DISPLAY INVISIBLE (-7675 3800);
FORCEPROP 2 LAST CDS_SEC 1
J 0
(-7625 4000);
PAINT MONO (-7625 4000);
DISPLAY INVISIBLE (-7625 4000);
FORCEPROP 2 LAST $SEC 1
J 0
(-7625 4000);
PAINT MONO (-7625 4000);
DISPLAY INVISIBLE (-7625 4000);
FORCEPROP 1 LAST PATH I140
J 0
(-7625 3950);
DISPLAY 0.978723 (-7625 3950);
PAINT WHITE (-7625 3950);
DISPLAY INVISIBLE (-7625 3950);
FORCEPROP 2 LAST ROOM PVCCIN_CPU0_DECAP_VR
J 0
(-7625 3950);
DISPLAY 1.021277 (-7625 3950);
PAINT ORANGE (-7625 3950);
DISPLAY INVISIBLE (-7625 3950);
FORCEADD PVCCIN_CPU0..1
(-7625 3450);
FORCEPROP 3 LASTPIN (-7625 3400) SIG_NAME PVCCIN_CPU0\g
J 0
(-7615 3410);
DISPLAY 0.659574 (-7615 3410);
PAINT MONO (-7615 3410);
DISPLAY INVISIBLE (-7615 3410);
FORCEPROP 1 LAST VOLTAGE 2.0V
J 0
(-7670 3407);
DISPLAY 0.340426 (-7670 3407);
PAINT SKYBLUE (-7670 3407);
DISPLAY INVISIBLE (-7670 3407);
FORCEPROP 2 LAST CDS_LIB mstr_symbols
J 0
(-7625 3450);
PAINT ORANGE (-7625 3450);
DISPLAY INVISIBLE (-7625 3450);
FORCEPROP 1 LAST BODY_TYPE PLUMBING
J 0
(-7670 3407);
DISPLAY 0.340426 (-7670 3407);
PAINT GREEN (-7670 3407);
DISPLAY INVISIBLE (-7670 3407);
FORCEPROP 1 LAST PATH I141
J 0
(-7575 3475);
DISPLAY 0.872340 (-7575 3475);
PAINT AQUA (-7575 3475);
DISPLAY INVISIBLE (-7575 3475);
FORCEPROP 1 LAST HDL_POWER PVCCIN_CPU0
J 1
(-7625 3500);
DISPLAY 0.872340 (-7625 3500);
PAINT GREEN (-7625 3500);
DISPLAY INVISIBLE (-7625 3500);
FORCEADD CAP_A..1
(-7625 3175);
FORCEPROP 1 LAST LOCATION C5D44
J 0
(-7575 3275);
DISPLAY 0.617021 (-7575 3275);
PAINT AQUA (-7575 3275);
FORCEPROP 1 LAST PART_NUMBER E15431-004
J 0
(-7575 3025);
DISPLAY 0.617021 (-7575 3025);
PAINT BLUE (-7575 3025);
FORCEPROP 1 LAST VALUE 22.0UF
J 0
(-7575 3225);
DISPLAY 0.617021 (-7575 3225);
PAINT SKYBLUE (-7575 3225);
FORCEPROP 1 LAST TOLERANCE 20%
J 0
(-7575 3125);
DISPLAY 0.617021 (-7575 3125);
PAINT SKYBLUE (-7575 3125);
FORCEPROP 1 LAST PACK_TYPE 0603V
J 0
(-7575 2975);
DISPLAY 0.617021 (-7575 2975);
PAINT SKYBLUE (-7575 2975);
FORCEPROP 1 LAST VOLTAGE 4V
J 0
(-7575 3175);
DISPLAY 0.617021 (-7575 3175);
PAINT SKYBLUE (-7575 3175);
FORCEPROP 1 LAST MATERIAL X6S
J 0
(-7575 3075);
DISPLAY 0.617021 (-7575 3075);
PAINT SKYBLUE (-7575 3075);
FORCEPROP 1 LASTPIN (-7625 3275) $PN 1
J 0
(-7615 3255);
DISPLAY 0.617021 (-7615 3255);
PAINT GREEN (-7615 3255);
FORCEPROP 1 LASTPIN (-7625 3075) $PN 2
J 0
(-7615 3055);
DISPLAY 0.617021 (-7615 3055);
PAINT GREEN (-7615 3055);
FORCEPROP 2 LAST CDS_LOCATION C5D44
J 0
(-7575 3275);
DISPLAY 0.617021 (-7575 3275);
PAINT AQUA (-7575 3275);
DISPLAY INVISIBLE (-7575 3275);
FORCEPROP 2 LAST BOM_COST PROC_SOCKET
J 0
(-7575 3375);
DISPLAY 1.021277 (-7575 3375);
PAINT ORANGE (-7575 3375);
DISPLAY INVISIBLE (-7575 3375);
FORCEPROP 2 LAST CDS_LIB dev_discrete
J 0
(-7625 3175);
PAINT ORANGE (-7625 3175);
DISPLAY INVISIBLE (-7625 3175);
FORCEPROP 2 LAST CDS_SEC 1
J 0
(-7575 3375);
PAINT MONO (-7575 3375);
DISPLAY INVISIBLE (-7575 3375);
FORCEPROP 2 LAST $SEC 1
J 0
(-7575 3375);
PAINT MONO (-7575 3375);
DISPLAY INVISIBLE (-7575 3375);
FORCEPROP 1 LAST PATH I142
J 0
(-7575 3325);
DISPLAY 0.978723 (-7575 3325);
PAINT WHITE (-7575 3325);
DISPLAY INVISIBLE (-7575 3325);
FORCEPROP 2 LAST ROOM PVCCIN_CPU0_DECAP_VR
J 0
(-7575 3325);
DISPLAY 1.021277 (-7575 3325);
PAINT ORANGE (-7575 3325);
DISPLAY INVISIBLE (-7575 3325);
FORCEADD VCC_CORE..1
(-3875 4750);
FORCEPROP 3 LASTPIN (-3875 4700) SIG_NAME PVCCMCP_CPU0\g
J 0
(-3865 4710);
DISPLAY 0.659574 (-3865 4710);
PAINT MONO (-3865 4710);
DISPLAY INVISIBLE (-3865 4710);
FORCEPROP 1 LAST HDL_POWER PVCCMCP_CPU0
J 1
(-3875 4800);
DISPLAY 0.617021 (-3875 4800);
PAINT GREEN (-3875 4800);
FORCEPROP 2 LAST CDS_LIB mstr_symbols
J 0
(-3875 4750);
PAINT ORANGE (-3875 4750);
DISPLAY INVISIBLE (-3875 4750);
FORCEPROP 1 LAST PATH I144
J 0
(-3825 4775);
DISPLAY 0.872340 (-3825 4775);
PAINT AQUA (-3825 4775);
DISPLAY INVISIBLE (-3825 4775);
FORCEADD CAP_A..1
(-2850 3775);
FORCEPROP 1 LAST LOCATION C6D9
J 0
(-2800 3875);
DISPLAY 0.617021 (-2800 3875);
PAINT AQUA (-2800 3875);
FORCEPROP 1 LAST PART_NUMBER E15431-004
J 0
(-2800 3625);
DISPLAY 0.617021 (-2800 3625);
PAINT BLUE (-2800 3625);
FORCEPROP 1 LAST VALUE 22.0UF
J 0
(-2800 3825);
DISPLAY 0.617021 (-2800 3825);
PAINT SKYBLUE (-2800 3825);
FORCEPROP 1 LAST TOLERANCE 20%
J 0
(-2800 3725);
DISPLAY 0.617021 (-2800 3725);
PAINT SKYBLUE (-2800 3725);
FORCEPROP 1 LAST PACK_TYPE 0603V
J 0
(-2800 3575);
DISPLAY 0.617021 (-2800 3575);
PAINT SKYBLUE (-2800 3575);
FORCEPROP 1 LAST VOLTAGE 4V
J 0
(-2800 3775);
DISPLAY 0.617021 (-2800 3775);
PAINT SKYBLUE (-2800 3775);
FORCEPROP 1 LAST MATERIAL X6S
J 0
(-2800 3675);
DISPLAY 0.617021 (-2800 3675);
PAINT SKYBLUE (-2800 3675);
FORCEPROP 1 LASTPIN (-2850 3875) $PN 1
J 0
(-2840 3855);
DISPLAY 0.617021 (-2840 3855);
PAINT ORANGE (-2840 3855);
FORCEPROP 1 LASTPIN (-2850 3675) $PN 2
J 0
(-2840 3655);
DISPLAY 0.617021 (-2840 3655);
PAINT ORANGE (-2840 3655);
FORCEPROP 2 LAST CDS_LOCATION C6D9
J 0
(-2800 3875);
DISPLAY 0.617021 (-2800 3875);
PAINT AQUA (-2800 3875);
DISPLAY INVISIBLE (-2800 3875);
FORCEPROP 2 LAST CDS_LIB dev_discrete
J 0
(-2850 3775);
PAINT ORANGE (-2850 3775);
DISPLAY INVISIBLE (-2850 3775);
FORCEPROP 2 LAST CDS_SEC 1
J 0
(-2800 3975);
PAINT MONO (-2800 3975);
DISPLAY INVISIBLE (-2800 3975);
FORCEPROP 2 LAST $SEC 1
J 0
(-2800 3975);
PAINT MONO (-2800 3975);
DISPLAY INVISIBLE (-2800 3975);
FORCEPROP 1 LAST PATH I145
J 0
(-2800 3925);
DISPLAY 0.978723 (-2800 3925);
PAINT WHITE (-2800 3925);
DISPLAY INVISIBLE (-2800 3925);
FORCEPROP 0 LAST ROOM PVCCIN_CPU0_DECAP_VR
J 0
(-2800 3925);
DISPLAY 1.021277 (-2800 3925);
PAINT ORANGE (-2800 3925);
DISPLAY INVISIBLE (-2800 3925);
FORCEADD CAP_A..1
(-3125 3775);
FORCEPROP 1 LAST LOCATION C6D10
J 0
(-3075 3875);
DISPLAY 0.617021 (-3075 3875);
PAINT AQUA (-3075 3875);
FORCEPROP 1 LAST PART_NUMBER E15431-004
J 0
(-3075 3625);
DISPLAY 0.617021 (-3075 3625);
PAINT BLUE (-3075 3625);
FORCEPROP 1 LAST VALUE 22.0UF
J 0
(-3075 3825);
DISPLAY 0.617021 (-3075 3825);
PAINT SKYBLUE (-3075 3825);
FORCEPROP 1 LAST TOLERANCE 20%
J 0
(-3075 3725);
DISPLAY 0.617021 (-3075 3725);
PAINT SKYBLUE (-3075 3725);
FORCEPROP 1 LAST PACK_TYPE 0603V
J 0
(-3075 3575);
DISPLAY 0.617021 (-3075 3575);
PAINT SKYBLUE (-3075 3575);
FORCEPROP 1 LAST VOLTAGE 4V
J 0
(-3075 3775);
DISPLAY 0.617021 (-3075 3775);
PAINT SKYBLUE (-3075 3775);
FORCEPROP 1 LAST MATERIAL X6S
J 0
(-3075 3675);
DISPLAY 0.617021 (-3075 3675);
PAINT SKYBLUE (-3075 3675);
FORCEPROP 1 LASTPIN (-3125 3875) $PN 1
J 0
(-3115 3855);
DISPLAY 0.617021 (-3115 3855);
PAINT ORANGE (-3115 3855);
FORCEPROP 1 LASTPIN (-3125 3675) $PN 2
J 0
(-3115 3655);
DISPLAY 0.617021 (-3115 3655);
PAINT ORANGE (-3115 3655);
FORCEPROP 2 LAST CDS_LOCATION C6D10
J 0
(-3075 3875);
DISPLAY 0.617021 (-3075 3875);
PAINT AQUA (-3075 3875);
DISPLAY INVISIBLE (-3075 3875);
FORCEPROP 2 LAST CDS_LIB dev_discrete
J 0
(-3125 3775);
PAINT ORANGE (-3125 3775);
DISPLAY INVISIBLE (-3125 3775);
FORCEPROP 2 LAST CDS_SEC 1
J 0
(-3075 3975);
PAINT MONO (-3075 3975);
DISPLAY INVISIBLE (-3075 3975);
FORCEPROP 2 LAST $SEC 1
J 0
(-3075 3975);
PAINT MONO (-3075 3975);
DISPLAY INVISIBLE (-3075 3975);
FORCEPROP 1 LAST PATH I147
J 0
(-3075 3925);
DISPLAY 0.978723 (-3075 3925);
PAINT WHITE (-3075 3925);
DISPLAY INVISIBLE (-3075 3925);
FORCEPROP 0 LAST ROOM PVCCIN_CPU0_DECAP_VR
J 0
(-3075 3925);
DISPLAY 1.021277 (-3075 3925);
PAINT ORANGE (-3075 3925);
DISPLAY INVISIBLE (-3075 3925);
FORCEADD CAP..1
(-4425 2175);
FORCEPROP 1 LAST LOCATION C5P30
J 0
(-4375 2275);
DISPLAY 0.617021 (-4375 2275);
PAINT AQUA (-4375 2275);
FORCEPROP 1 LAST PART_NUMBER C95333-006
J 0
(-4375 2025);
DISPLAY 0.617021 (-4375 2025);
PAINT BLUE (-4375 2025);
FORCEPROP 1 LAST VALUE 47UF
J 0
(-4375 2225);
DISPLAY 0.617021 (-4375 2225);
PAINT SKYBLUE (-4375 2225);
FORCEPROP 1 LAST TOLERANCE 20%
J 0
(-4375 2125);
DISPLAY 0.617021 (-4375 2125);
PAINT SKYBLUE (-4375 2125);
FORCEPROP 1 LAST PACK_TYPE 0805
J 0
(-4375 1975);
DISPLAY 0.617021 (-4375 1975);
PAINT SKYBLUE (-4375 1975);
FORCEPROP 1 LAST VOLTAGE 4V
J 0
(-4375 2175);
DISPLAY 0.617021 (-4375 2175);
PAINT SKYBLUE (-4375 2175);
FORCEPROP 1 LAST MATERIAL X6S
J 0
(-4375 2075);
DISPLAY 0.617021 (-4375 2075);
PAINT SKYBLUE (-4375 2075);
FORCEPROP 1 LASTPIN (-4425 2075) $PN 2
J 0
(-4415 2055);
DISPLAY 0.617021 (-4415 2055);
PAINT ORANGE (-4415 2055);
FORCEPROP 1 LASTPIN (-4425 2275) $PN 1
J 0
(-4415 2255);
DISPLAY 0.617021 (-4415 2255);
PAINT ORANGE (-4415 2255);
FORCEPROP 2 LAST CDS_LIB mstr_discrete
J 0
(-4425 2175);
PAINT ORANGE (-4425 2175);
DISPLAY INVISIBLE (-4425 2175);
FORCEPROP 2 LAST CDS_SEC 1
J 0
(-4375 2375);
PAINT MONO (-4375 2375);
DISPLAY INVISIBLE (-4375 2375);
FORCEPROP 2 LAST $SEC 1
J 0
(-4375 2375);
PAINT MONO (-4375 2375);
DISPLAY INVISIBLE (-4375 2375);
FORCEPROP 2 LAST CDS_LOCATION C5P30
J 0
(-4375 2275);
DISPLAY 0.617021 (-4375 2275);
PAINT AQUA (-4375 2275);
DISPLAY INVISIBLE (-4375 2275);
FORCEPROP 1 LAST PATH I148
J 0
(-4375 2325);
DISPLAY 0.978723 (-4375 2325);
PAINT WHITE (-4375 2325);
DISPLAY INVISIBLE (-4375 2325);
FORCEPROP 0 LAST ROOM PVCCIN_CPU0_DECAP_VR
J 0
(-4375 2325);
DISPLAY 1.021277 (-4375 2325);
PAINT ORANGE (-4375 2325);
DISPLAY INVISIBLE (-4375 2325);
FORCEADD CAP..1
(-4675 2175);
FORCEPROP 1 LAST LOCATION C5P29
J 0
(-4625 2275);
DISPLAY 0.617021 (-4625 2275);
PAINT AQUA (-4625 2275);
FORCEPROP 1 LAST PART_NUMBER C95333-006
J 0
(-4625 2025);
DISPLAY 0.617021 (-4625 2025);
PAINT BLUE (-4625 2025);
FORCEPROP 1 LAST VALUE 47UF
J 0
(-4625 2225);
DISPLAY 0.617021 (-4625 2225);
PAINT SKYBLUE (-4625 2225);
FORCEPROP 1 LAST TOLERANCE 20%
J 0
(-4625 2125);
DISPLAY 0.617021 (-4625 2125);
PAINT SKYBLUE (-4625 2125);
FORCEPROP 1 LAST PACK_TYPE 0805
J 0
(-4625 1975);
DISPLAY 0.617021 (-4625 1975);
PAINT SKYBLUE (-4625 1975);
FORCEPROP 1 LAST VOLTAGE 4V
J 0
(-4625 2175);
DISPLAY 0.617021 (-4625 2175);
PAINT SKYBLUE (-4625 2175);
FORCEPROP 1 LAST MATERIAL X6S
J 0
(-4625 2075);
DISPLAY 0.617021 (-4625 2075);
PAINT SKYBLUE (-4625 2075);
FORCEPROP 1 LASTPIN (-4675 2075) $PN 2
J 0
(-4665 2055);
DISPLAY 0.617021 (-4665 2055);
PAINT ORANGE (-4665 2055);
FORCEPROP 1 LASTPIN (-4675 2275) $PN 1
J 0
(-4665 2255);
DISPLAY 0.617021 (-4665 2255);
PAINT ORANGE (-4665 2255);
FORCEPROP 2 LAST CDS_LIB mstr_discrete
J 0
(-4675 2175);
PAINT ORANGE (-4675 2175);
DISPLAY INVISIBLE (-4675 2175);
FORCEPROP 2 LAST CDS_SEC 1
J 0
(-4625 2375);
PAINT MONO (-4625 2375);
DISPLAY INVISIBLE (-4625 2375);
FORCEPROP 2 LAST $SEC 1
J 0
(-4625 2375);
PAINT MONO (-4625 2375);
DISPLAY INVISIBLE (-4625 2375);
FORCEPROP 2 LAST CDS_LOCATION C5P29
J 0
(-4625 2275);
DISPLAY 0.617021 (-4625 2275);
PAINT AQUA (-4625 2275);
DISPLAY INVISIBLE (-4625 2275);
FORCEPROP 1 LAST PATH I149
J 0
(-4625 2325);
DISPLAY 0.978723 (-4625 2325);
PAINT WHITE (-4625 2325);
DISPLAY INVISIBLE (-4625 2325);
FORCEPROP 0 LAST ROOM PVCCIN_CPU0_DECAP_VR
J 0
(-4625 2325);
DISPLAY 1.021277 (-4625 2325);
PAINT ORANGE (-4625 2325);
DISPLAY INVISIBLE (-4625 2325);
FORCEADD CAP_A..1
(-2575 4475);
FORCEPROP 1 LAST LOCATION C5D36
J 0
(-2525 4575);
DISPLAY 0.617021 (-2525 4575);
PAINT AQUA (-2525 4575);
FORCEPROP 1 LAST PART_NUMBER E15431-004
J 0
(-2525 4325);
DISPLAY 0.617021 (-2525 4325);
PAINT BLUE (-2525 4325);
FORCEPROP 1 LAST VALUE 22.0UF
J 0
(-2525 4525);
DISPLAY 0.617021 (-2525 4525);
PAINT SKYBLUE (-2525 4525);
FORCEPROP 1 LAST TOLERANCE 20%
J 0
(-2525 4425);
DISPLAY 0.617021 (-2525 4425);
PAINT SKYBLUE (-2525 4425);
FORCEPROP 1 LAST PACK_TYPE 0603V
J 0
(-2525 4275);
DISPLAY 0.617021 (-2525 4275);
PAINT SKYBLUE (-2525 4275);
FORCEPROP 1 LAST VOLTAGE 4V
J 0
(-2525 4475);
DISPLAY 0.617021 (-2525 4475);
PAINT SKYBLUE (-2525 4475);
FORCEPROP 1 LAST MATERIAL X6S
J 0
(-2525 4375);
DISPLAY 0.617021 (-2525 4375);
PAINT SKYBLUE (-2525 4375);
FORCEPROP 1 LASTPIN (-2575 4575) $PN 1
J 0
(-2565 4555);
DISPLAY 0.617021 (-2565 4555);
PAINT ORANGE (-2565 4555);
FORCEPROP 1 LASTPIN (-2575 4375) $PN 2
J 0
(-2565 4355);
DISPLAY 0.617021 (-2565 4355);
PAINT ORANGE (-2565 4355);
FORCEPROP 2 LAST CDS_LOCATION C5D36
J 0
(-2525 4575);
DISPLAY 0.617021 (-2525 4575);
PAINT AQUA (-2525 4575);
DISPLAY INVISIBLE (-2525 4575);
FORCEPROP 2 LAST BOM_COST PROC_SOCKET
J 0
(-2525 4675);
DISPLAY 1.021277 (-2525 4675);
PAINT ORANGE (-2525 4675);
DISPLAY INVISIBLE (-2525 4675);
FORCEPROP 2 LAST CDS_LIB dev_discrete
J 0
(-2575 4475);
PAINT ORANGE (-2575 4475);
DISPLAY INVISIBLE (-2575 4475);
FORCEPROP 2 LAST CDS_SEC 1
J 0
(-2525 4675);
PAINT MONO (-2525 4675);
DISPLAY INVISIBLE (-2525 4675);
FORCEPROP 2 LAST $SEC 1
J 0
(-2525 4675);
PAINT MONO (-2525 4675);
DISPLAY INVISIBLE (-2525 4675);
FORCEPROP 1 LAST PATH I151
J 0
(-2525 4625);
DISPLAY 0.978723 (-2525 4625);
PAINT WHITE (-2525 4625);
DISPLAY INVISIBLE (-2525 4625);
FORCEPROP 2 LAST ROOM PVCCIN_CPU0_DECAP_VR
J 0
(-2525 4625);
DISPLAY 1.021277 (-2525 4625);
PAINT ORANGE (-2525 4625);
DISPLAY INVISIBLE (-2525 4625);
FORCEADD CAP_A..1
(-2275 4450);
FORCEPROP 1 LAST LOCATION C5D49
J 0
(-2225 4550);
DISPLAY 0.617021 (-2225 4550);
PAINT AQUA (-2225 4550);
FORCEPROP 1 LAST PART_NUMBER E15431-004
J 0
(-2225 4300);
DISPLAY 0.617021 (-2225 4300);
PAINT BLUE (-2225 4300);
FORCEPROP 1 LAST VALUE 22.0UF
J 0
(-2225 4500);
DISPLAY 0.617021 (-2225 4500);
PAINT SKYBLUE (-2225 4500);
FORCEPROP 1 LAST TOLERANCE 20%
J 0
(-2225 4400);
DISPLAY 0.617021 (-2225 4400);
PAINT SKYBLUE (-2225 4400);
FORCEPROP 1 LAST PACK_TYPE 0603V
J 0
(-2225 4250);
DISPLAY 0.617021 (-2225 4250);
PAINT SKYBLUE (-2225 4250);
FORCEPROP 1 LAST VOLTAGE 4V
J 0
(-2225 4450);
DISPLAY 0.617021 (-2225 4450);
PAINT SKYBLUE (-2225 4450);
FORCEPROP 1 LAST MATERIAL X6S
J 0
(-2225 4350);
DISPLAY 0.617021 (-2225 4350);
PAINT SKYBLUE (-2225 4350);
FORCEPROP 1 LASTPIN (-2275 4550) $PN 1
J 0
(-2265 4530);
DISPLAY 0.617021 (-2265 4530);
PAINT ORANGE (-2265 4530);
FORCEPROP 1 LASTPIN (-2275 4350) $PN 2
J 0
(-2265 4330);
DISPLAY 0.617021 (-2265 4330);
PAINT ORANGE (-2265 4330);
FORCEPROP 2 LAST CDS_LOCATION C5D49
J 0
(-2225 4550);
DISPLAY 0.617021 (-2225 4550);
PAINT AQUA (-2225 4550);
DISPLAY INVISIBLE (-2225 4550);
FORCEPROP 2 LAST BOM_COST PROC_SOCKET
J 0
(-2225 4650);
DISPLAY 1.021277 (-2225 4650);
PAINT ORANGE (-2225 4650);
DISPLAY INVISIBLE (-2225 4650);
FORCEPROP 2 LAST CDS_LIB dev_discrete
J 0
(-2275 4450);
PAINT ORANGE (-2275 4450);
DISPLAY INVISIBLE (-2275 4450);
FORCEPROP 2 LAST CDS_SEC 1
J 0
(-2225 4650);
PAINT MONO (-2225 4650);
DISPLAY INVISIBLE (-2225 4650);
FORCEPROP 2 LAST $SEC 1
J 0
(-2225 4650);
PAINT MONO (-2225 4650);
DISPLAY INVISIBLE (-2225 4650);
FORCEPROP 1 LAST PATH I152
J 0
(-2225 4600);
DISPLAY 0.978723 (-2225 4600);
PAINT WHITE (-2225 4600);
DISPLAY INVISIBLE (-2225 4600);
FORCEPROP 2 LAST ROOM PVCCIN_CPU0_DECAP_VR
J 0
(-2225 4600);
DISPLAY 1.021277 (-2225 4600);
PAINT ORANGE (-2225 4600);
DISPLAY INVISIBLE (-2225 4600);
FORCEADD CAP_A..1
(-525 4475);
FORCEPROP 1 LAST LOCATION C5D22
J 0
(-475 4575);
DISPLAY 0.617021 (-475 4575);
PAINT AQUA (-475 4575);
FORCEPROP 1 LAST PART_NUMBER E15431-004
J 0
(-475 4325);
DISPLAY 0.617021 (-475 4325);
PAINT BLUE (-475 4325);
FORCEPROP 1 LAST VALUE 22.0UF
J 0
(-475 4525);
DISPLAY 0.617021 (-475 4525);
PAINT SKYBLUE (-475 4525);
FORCEPROP 1 LAST TOLERANCE 20%
J 0
(-475 4425);
DISPLAY 0.617021 (-475 4425);
PAINT SKYBLUE (-475 4425);
FORCEPROP 1 LAST PACK_TYPE 0603V
J 0
(-475 4275);
DISPLAY 0.617021 (-475 4275);
PAINT SKYBLUE (-475 4275);
FORCEPROP 1 LAST VOLTAGE 4V
J 0
(-475 4475);
DISPLAY 0.617021 (-475 4475);
PAINT SKYBLUE (-475 4475);
FORCEPROP 1 LAST MATERIAL X6S
J 0
(-475 4375);
DISPLAY 0.617021 (-475 4375);
PAINT SKYBLUE (-475 4375);
FORCEPROP 1 LASTPIN (-525 4575) $PN 1
J 0
(-515 4555);
DISPLAY 0.617021 (-515 4555);
PAINT ORANGE (-515 4555);
FORCEPROP 1 LASTPIN (-525 4375) $PN 2
J 0
(-515 4355);
DISPLAY 0.617021 (-515 4355);
PAINT ORANGE (-515 4355);
FORCEPROP 2 LAST CDS_LOCATION C5D22
J 0
(-475 4575);
DISPLAY 0.617021 (-475 4575);
PAINT AQUA (-475 4575);
DISPLAY INVISIBLE (-475 4575);
FORCEPROP 2 LAST BOM_COST PROC_SOCKET
J 0
(-475 4675);
DISPLAY 1.021277 (-475 4675);
PAINT ORANGE (-475 4675);
DISPLAY INVISIBLE (-475 4675);
FORCEPROP 2 LAST CDS_LIB dev_discrete
J 0
(-525 4475);
PAINT ORANGE (-525 4475);
DISPLAY INVISIBLE (-525 4475);
FORCEPROP 2 LAST CDS_SEC 1
J 0
(-475 4675);
PAINT MONO (-475 4675);
DISPLAY INVISIBLE (-475 4675);
FORCEPROP 2 LAST $SEC 1
J 0
(-475 4675);
PAINT MONO (-475 4675);
DISPLAY INVISIBLE (-475 4675);
FORCEPROP 1 LAST PATH I153
J 0
(-475 4625);
DISPLAY 0.978723 (-475 4625);
PAINT WHITE (-475 4625);
DISPLAY INVISIBLE (-475 4625);
FORCEPROP 2 LAST ROOM PVCCIN_CPU0_DECAP_VR
J 0
(-475 4625);
DISPLAY 1.021277 (-475 4625);
PAINT ORANGE (-475 4625);
DISPLAY INVISIBLE (-475 4625);
FORCEADD CAP_A..1
(-4450 4475);
FORCEPROP 1 LAST LOCATION C5D26
J 0
(-4400 4575);
DISPLAY 0.617021 (-4400 4575);
PAINT AQUA (-4400 4575);
FORCEPROP 1 LAST PART_NUMBER E15431-004
J 0
(-4400 4325);
DISPLAY 0.617021 (-4400 4325);
PAINT BLUE (-4400 4325);
FORCEPROP 1 LAST VALUE 22.0UF
J 0
(-4400 4525);
DISPLAY 0.617021 (-4400 4525);
PAINT SKYBLUE (-4400 4525);
FORCEPROP 1 LAST TOLERANCE 20%
J 0
(-4400 4425);
DISPLAY 0.617021 (-4400 4425);
PAINT SKYBLUE (-4400 4425);
FORCEPROP 1 LAST PACK_TYPE 0603V
J 0
(-4400 4275);
DISPLAY 0.617021 (-4400 4275);
PAINT SKYBLUE (-4400 4275);
FORCEPROP 1 LAST VOLTAGE 4V
J 0
(-4400 4475);
DISPLAY 0.617021 (-4400 4475);
PAINT SKYBLUE (-4400 4475);
FORCEPROP 1 LAST MATERIAL X6S
J 0
(-4400 4375);
DISPLAY 0.617021 (-4400 4375);
PAINT SKYBLUE (-4400 4375);
FORCEPROP 1 LASTPIN (-4450 4575) $PN 1
J 0
(-4440 4555);
DISPLAY 0.617021 (-4440 4555);
PAINT ORANGE (-4440 4555);
FORCEPROP 1 LASTPIN (-4450 4375) $PN 2
J 0
(-4440 4355);
DISPLAY 0.617021 (-4440 4355);
PAINT ORANGE (-4440 4355);
FORCEPROP 2 LAST CDS_LOCATION C5D26
J 0
(-4400 4575);
DISPLAY 0.617021 (-4400 4575);
PAINT AQUA (-4400 4575);
DISPLAY INVISIBLE (-4400 4575);
FORCEPROP 2 LAST BOM_COST PROC_SOCKET
J 0
(-4400 4675);
DISPLAY 1.021277 (-4400 4675);
PAINT ORANGE (-4400 4675);
DISPLAY INVISIBLE (-4400 4675);
FORCEPROP 2 LAST CDS_LIB dev_discrete
J 0
(-4450 4475);
PAINT ORANGE (-4450 4475);
DISPLAY INVISIBLE (-4450 4475);
FORCEPROP 2 LAST CDS_SEC 1
J 0
(-4400 4675);
PAINT MONO (-4400 4675);
DISPLAY INVISIBLE (-4400 4675);
FORCEPROP 2 LAST $SEC 1
J 0
(-4400 4675);
PAINT MONO (-4400 4675);
DISPLAY INVISIBLE (-4400 4675);
FORCEPROP 1 LAST PATH I154
J 0
(-4400 4625);
DISPLAY 0.978723 (-4400 4625);
PAINT WHITE (-4400 4625);
DISPLAY INVISIBLE (-4400 4625);
FORCEPROP 2 LAST ROOM PVCCIN_CPU0_DECAP_VR
J 0
(-4400 4625);
DISPLAY 1.021277 (-4400 4625);
PAINT ORANGE (-4400 4625);
DISPLAY INVISIBLE (-4400 4625);
FORCEADD CAP_A..1
(-4425 3800);
FORCEPROP 1 LAST LOCATION C5D25
J 0
(-4375 3900);
DISPLAY 0.617021 (-4375 3900);
PAINT AQUA (-4375 3900);
FORCEPROP 1 LAST PART_NUMBER E15431-004
J 0
(-4375 3650);
DISPLAY 0.617021 (-4375 3650);
PAINT BLUE (-4375 3650);
FORCEPROP 1 LAST VALUE 22.0UF
J 0
(-4375 3850);
DISPLAY 0.617021 (-4375 3850);
PAINT SKYBLUE (-4375 3850);
FORCEPROP 1 LAST TOLERANCE 20%
J 0
(-4375 3750);
DISPLAY 0.617021 (-4375 3750);
PAINT SKYBLUE (-4375 3750);
FORCEPROP 1 LAST PACK_TYPE 0603V
J 0
(-4375 3600);
DISPLAY 0.617021 (-4375 3600);
PAINT SKYBLUE (-4375 3600);
FORCEPROP 1 LAST VOLTAGE 4V
J 0
(-4375 3800);
DISPLAY 0.617021 (-4375 3800);
PAINT SKYBLUE (-4375 3800);
FORCEPROP 1 LAST MATERIAL X6S
J 0
(-4375 3700);
DISPLAY 0.617021 (-4375 3700);
PAINT SKYBLUE (-4375 3700);
FORCEPROP 1 LASTPIN (-4425 3900) $PN 1
J 0
(-4415 3880);
DISPLAY 0.617021 (-4415 3880);
PAINT ORANGE (-4415 3880);
FORCEPROP 1 LASTPIN (-4425 3700) $PN 2
J 0
(-4415 3680);
DISPLAY 0.617021 (-4415 3680);
PAINT ORANGE (-4415 3680);
FORCEPROP 2 LAST CDS_LOCATION C5D25
J 0
(-4375 3900);
DISPLAY 0.617021 (-4375 3900);
PAINT AQUA (-4375 3900);
DISPLAY INVISIBLE (-4375 3900);
FORCEPROP 2 LAST BOM_COST PROC_SOCKET
J 0
(-4375 4000);
DISPLAY 1.021277 (-4375 4000);
PAINT ORANGE (-4375 4000);
DISPLAY INVISIBLE (-4375 4000);
FORCEPROP 2 LAST CDS_LIB dev_discrete
J 0
(-4425 3800);
PAINT ORANGE (-4425 3800);
DISPLAY INVISIBLE (-4425 3800);
FORCEPROP 2 LAST CDS_SEC 1
J 0
(-4375 4000);
PAINT MONO (-4375 4000);
DISPLAY INVISIBLE (-4375 4000);
FORCEPROP 2 LAST $SEC 1
J 0
(-4375 4000);
PAINT MONO (-4375 4000);
DISPLAY INVISIBLE (-4375 4000);
FORCEPROP 1 LAST PATH I155
J 0
(-4375 3950);
DISPLAY 0.978723 (-4375 3950);
PAINT WHITE (-4375 3950);
DISPLAY INVISIBLE (-4375 3950);
FORCEPROP 2 LAST ROOM PVCCIN_CPU0_DECAP_VR
J 0
(-4375 3950);
DISPLAY 1.021277 (-4375 3950);
PAINT ORANGE (-4375 3950);
DISPLAY INVISIBLE (-4375 3950);
FORCEADD CAP_A..1
(-4450 3200);
FORCEPROP 1 LAST LOCATION C5D45
J 0
(-4400 3300);
DISPLAY 0.617021 (-4400 3300);
PAINT AQUA (-4400 3300);
FORCEPROP 1 LAST PART_NUMBER E15431-004
J 0
(-4400 3050);
DISPLAY 0.617021 (-4400 3050);
PAINT BLUE (-4400 3050);
FORCEPROP 1 LAST VALUE 22.0UF
J 0
(-4400 3250);
DISPLAY 0.617021 (-4400 3250);
PAINT SKYBLUE (-4400 3250);
FORCEPROP 1 LAST TOLERANCE 20%
J 0
(-4400 3150);
DISPLAY 0.617021 (-4400 3150);
PAINT SKYBLUE (-4400 3150);
FORCEPROP 1 LAST PACK_TYPE 0603V
J 0
(-4400 3000);
DISPLAY 0.617021 (-4400 3000);
PAINT SKYBLUE (-4400 3000);
FORCEPROP 1 LAST VOLTAGE 4V
J 0
(-4400 3200);
DISPLAY 0.617021 (-4400 3200);
PAINT SKYBLUE (-4400 3200);
FORCEPROP 1 LAST MATERIAL X6S
J 0
(-4400 3100);
DISPLAY 0.617021 (-4400 3100);
PAINT SKYBLUE (-4400 3100);
FORCEPROP 1 LASTPIN (-4450 3300) $PN 1
J 0
(-4440 3280);
DISPLAY 0.617021 (-4440 3280);
PAINT ORANGE (-4440 3280);
FORCEPROP 1 LASTPIN (-4450 3100) $PN 2
J 0
(-4440 3080);
DISPLAY 0.617021 (-4440 3080);
PAINT ORANGE (-4440 3080);
FORCEPROP 2 LAST CDS_LOCATION C5D45
J 0
(-4400 3300);
DISPLAY 0.617021 (-4400 3300);
PAINT AQUA (-4400 3300);
DISPLAY INVISIBLE (-4400 3300);
FORCEPROP 2 LAST BOM_COST PROC_SOCKET
J 0
(-4400 3400);
DISPLAY 1.021277 (-4400 3400);
PAINT ORANGE (-4400 3400);
DISPLAY INVISIBLE (-4400 3400);
FORCEPROP 2 LAST CDS_LIB dev_discrete
J 0
(-4450 3200);
PAINT ORANGE (-4450 3200);
DISPLAY INVISIBLE (-4450 3200);
FORCEPROP 2 LAST CDS_SEC 1
J 0
(-4400 3400);
PAINT MONO (-4400 3400);
DISPLAY INVISIBLE (-4400 3400);
FORCEPROP 2 LAST $SEC 1
J 0
(-4400 3400);
PAINT MONO (-4400 3400);
DISPLAY INVISIBLE (-4400 3400);
FORCEPROP 1 LAST PATH I156
J 0
(-4400 3350);
DISPLAY 0.978723 (-4400 3350);
PAINT WHITE (-4400 3350);
DISPLAY INVISIBLE (-4400 3350);
FORCEPROP 2 LAST ROOM PVCCIN_CPU0_DECAP_VR
J 0
(-4400 3350);
DISPLAY 1.021277 (-4400 3350);
PAINT ORANGE (-4400 3350);
DISPLAY INVISIBLE (-4400 3350);
FORCEADD VCC_CORE..1
(-4675 2525);
FORCEPROP 3 LASTPIN (-4675 2475) SIG_NAME PVCCMCP_CPU0\g
J 0
(-4665 2485);
DISPLAY 0.659574 (-4665 2485);
PAINT MONO (-4665 2485);
DISPLAY INVISIBLE (-4665 2485);
FORCEPROP 1 LAST HDL_POWER PVCCMCP_CPU0
J 1
(-4675 2575);
DISPLAY 0.617021 (-4675 2575);
PAINT GREEN (-4675 2575);
FORCEPROP 2 LAST CDS_LIB mstr_symbols
J 0
(-4675 2525);
PAINT ORANGE (-4675 2525);
DISPLAY INVISIBLE (-4675 2525);
FORCEPROP 1 LAST PATH I159
J 0
(-4625 2550);
DISPLAY 0.872340 (-4625 2550);
PAINT AQUA (-4625 2550);
DISPLAY INVISIBLE (-4625 2550);
FORCEADD PVCCIO_CPU0..1
(-3175 1250);
FORCEPROP 3 LASTPIN (-3175 1200) SIG_NAME PVCCIO_CPU0\g
J 0
(-3165 1210);
DISPLAY 0.659574 (-3165 1210);
PAINT MONO (-3165 1210);
DISPLAY INVISIBLE (-3165 1210);
FORCEPROP 1 LAST VOLTAGE 1.1V
J 0
(-3220 1207);
DISPLAY 0.340426 (-3220 1207);
PAINT SKYBLUE (-3220 1207);
DISPLAY INVISIBLE (-3220 1207);
FORCEPROP 2 LAST CDS_LIB mstr_symbols
J 0
(-3175 1250);
PAINT ORANGE (-3175 1250);
DISPLAY INVISIBLE (-3175 1250);
FORCEPROP 1 LAST BODY_TYPE PLUMBING
J 0
(-3220 1207);
DISPLAY 0.340426 (-3220 1207);
PAINT GREEN (-3220 1207);
DISPLAY INVISIBLE (-3220 1207);
FORCEPROP 1 LAST PATH I16
J 0
(-3125 1275);
DISPLAY 0.872340 (-3125 1275);
PAINT AQUA (-3125 1275);
DISPLAY INVISIBLE (-3125 1275);
FORCEPROP 1 LAST HDL_POWER PVCCIO_CPU0
J 1
(-3175 1300);
DISPLAY 0.872340 (-3175 1300);
PAINT GREEN (-3175 1300);
DISPLAY INVISIBLE (-3175 1300);
FORCEADD CAP..1
(-1900 2150);
FORCEPROP 1 LAST VALUE 47UF
J 0
(-1850 2200);
DISPLAY 0.617021 (-1850 2200);
PAINT SKYBLUE (-1850 2200);
FORCEPROP 1 LAST TOLERANCE 20%
J 0
(-1850 2100);
DISPLAY 0.617021 (-1850 2100);
PAINT SKYBLUE (-1850 2100);
FORCEPROP 1 LAST PACK_TYPE 0805
J 0
(-1850 2000);
DISPLAY 0.617021 (-1850 2000);
PAINT SKYBLUE (-1850 2000);
FORCEPROP 1 LAST VOLTAGE 4V
J 0
(-1850 2150);
DISPLAY 0.617021 (-1850 2150);
PAINT SKYBLUE (-1850 2150);
FORCEPROP 1 LAST MATERIAL X6S
J 0
(-1850 2050);
DISPLAY 0.617021 (-1850 2050);
PAINT SKYBLUE (-1850 2050);
FORCEPROP 1 LASTPIN (-1900 2050) $PN 2
J 0
(-1890 2030);
DISPLAY 0.617021 (-1890 2030);
PAINT ORANGE (-1890 2030);
FORCEPROP 1 LASTPIN (-1900 2250) $PN 1
J 0
(-1890 2230);
DISPLAY 0.617021 (-1890 2230);
PAINT ORANGE (-1890 2230);
FORCEPROP 1 LAST PART_NUMBER C95333-006
R 1
J 0
(-1950 2000);
DISPLAY 0.617021 (-1950 2000);
PAINT BLUE (-1950 2000);
FORCEPROP 1 LAST LOCATION C5P31
J 0
(-1850 2250);
DISPLAY 0.617021 (-1850 2250);
PAINT AQUA (-1850 2250);
FORCEPROP 2 LAST CDS_LIB mstr_discrete
J 0
(-1900 2150);
PAINT ORANGE (-1900 2150);
DISPLAY INVISIBLE (-1900 2150);
FORCEPROP 2 LAST CDS_SEC 1
J 0
(-1850 2350);
PAINT MONO (-1850 2350);
DISPLAY INVISIBLE (-1850 2350);
FORCEPROP 2 LAST $SEC 1
J 0
(-1850 2350);
PAINT MONO (-1850 2350);
DISPLAY INVISIBLE (-1850 2350);
FORCEPROP 2 LAST CDS_LOCATION C5P31
J 0
(-1850 2250);
DISPLAY 0.617021 (-1850 2250);
PAINT AQUA (-1850 2250);
DISPLAY INVISIBLE (-1850 2250);
FORCEPROP 1 LAST PATH I162
J 0
(-1850 2300);
DISPLAY 0.978723 (-1850 2300);
PAINT WHITE (-1850 2300);
DISPLAY INVISIBLE (-1850 2300);
FORCEPROP 0 LAST ROOM PVCCIN_CPU0_DECAP_VR
J 0
(-1850 2300);
DISPLAY 1.021277 (-1850 2300);
PAINT ORANGE (-1850 2300);
DISPLAY INVISIBLE (-1850 2300);
FORCEADD CAP..1
(-1650 2150);
FORCEPROP 1 LAST LOCATION C4P2
J 0
(-1600 2250);
DISPLAY 0.617021 (-1600 2250);
PAINT AQUA (-1600 2250);
FORCEPROP 1 LAST PART_NUMBER C95333-006
R 1
J 0
(-1700 2000);
DISPLAY 0.617021 (-1700 2000);
PAINT BLUE (-1700 2000);
FORCEPROP 1 LAST VALUE 47UF
J 0
(-1600 2200);
DISPLAY 0.617021 (-1600 2200);
PAINT SKYBLUE (-1600 2200);
FORCEPROP 1 LAST TOLERANCE 20%
J 0
(-1600 2100);
DISPLAY 0.617021 (-1600 2100);
PAINT SKYBLUE (-1600 2100);
FORCEPROP 1 LAST PACK_TYPE 0805
J 0
(-1625 2000);
DISPLAY 0.617021 (-1625 2000);
PAINT SKYBLUE (-1625 2000);
FORCEPROP 1 LAST VOLTAGE 4V
J 0
(-1600 2150);
DISPLAY 0.617021 (-1600 2150);
PAINT SKYBLUE (-1600 2150);
FORCEPROP 1 LAST MATERIAL X6S
J 0
(-1600 2050);
DISPLAY 0.617021 (-1600 2050);
PAINT SKYBLUE (-1600 2050);
FORCEPROP 1 LASTPIN (-1650 2050) $PN 2
J 0
(-1640 2030);
DISPLAY 0.617021 (-1640 2030);
PAINT ORANGE (-1640 2030);
FORCEPROP 1 LASTPIN (-1650 2250) $PN 1
J 0
(-1640 2230);
DISPLAY 0.617021 (-1640 2230);
PAINT ORANGE (-1640 2230);
FORCEPROP 2 LAST CDS_LIB mstr_discrete
J 0
(-1650 2150);
PAINT ORANGE (-1650 2150);
DISPLAY INVISIBLE (-1650 2150);
FORCEPROP 2 LAST CDS_SEC 1
J 0
(-1600 2350);
PAINT MONO (-1600 2350);
DISPLAY INVISIBLE (-1600 2350);
FORCEPROP 2 LAST $SEC 1
J 0
(-1600 2350);
PAINT MONO (-1600 2350);
DISPLAY INVISIBLE (-1600 2350);
FORCEPROP 2 LAST CDS_LOCATION C4P2
J 0
(-1600 2250);
DISPLAY 0.617021 (-1600 2250);
PAINT AQUA (-1600 2250);
DISPLAY INVISIBLE (-1600 2250);
FORCEPROP 1 LAST PATH I163
J 0
(-1600 2300);
DISPLAY 0.978723 (-1600 2300);
PAINT WHITE (-1600 2300);
DISPLAY INVISIBLE (-1600 2300);
FORCEPROP 0 LAST ROOM PVCCIN_CPU0_DECAP_VR
J 0
(-1600 2300);
DISPLAY 1.021277 (-1600 2300);
PAINT ORANGE (-1600 2300);
DISPLAY INVISIBLE (-1600 2300);
FORCEADD CAP_A..1
(-2250 950);
FORCEPROP 1 LAST LOCATION C4P6
J 0
(-2200 1050);
DISPLAY 0.617021 (-2200 1050);
PAINT AQUA (-2200 1050);
FORCEPROP 1 LAST PART_NUMBER E15431-004
J 0
(-2200 800);
DISPLAY 0.617021 (-2200 800);
PAINT BLUE (-2200 800);
FORCEPROP 1 LAST VALUE 22.0UF
J 0
(-2200 1000);
DISPLAY 0.617021 (-2200 1000);
PAINT SKYBLUE (-2200 1000);
FORCEPROP 1 LAST TOLERANCE 20%
J 0
(-2200 900);
DISPLAY 0.617021 (-2200 900);
PAINT SKYBLUE (-2200 900);
FORCEPROP 1 LAST PACK_TYPE 0603V
J 0
(-2200 750);
DISPLAY 0.617021 (-2200 750);
PAINT SKYBLUE (-2200 750);
FORCEPROP 1 LAST VOLTAGE 4V
J 0
(-2200 950);
DISPLAY 0.617021 (-2200 950);
PAINT SKYBLUE (-2200 950);
FORCEPROP 1 LAST MATERIAL X6S
J 0
(-2200 850);
DISPLAY 0.617021 (-2200 850);
PAINT SKYBLUE (-2200 850);
FORCEPROP 1 LASTPIN (-2250 1050) $PN 1
J 0
(-2240 1030);
DISPLAY 0.617021 (-2240 1030);
PAINT ORANGE (-2240 1030);
FORCEPROP 1 LASTPIN (-2250 850) $PN 2
J 0
(-2240 830);
DISPLAY 0.617021 (-2240 830);
PAINT ORANGE (-2240 830);
FORCEPROP 2 LAST CDS_LOCATION C4P6
J 0
(-2200 1050);
DISPLAY 0.617021 (-2200 1050);
PAINT AQUA (-2200 1050);
DISPLAY INVISIBLE (-2200 1050);
FORCEPROP 2 LAST CDS_LIB dev_discrete
J 0
(-2250 950);
PAINT ORANGE (-2250 950);
DISPLAY INVISIBLE (-2250 950);
FORCEPROP 2 LAST CDS_SEC 1
J 0
(-2200 1150);
PAINT MONO (-2200 1150);
DISPLAY INVISIBLE (-2200 1150);
FORCEPROP 2 LAST $SEC 1
J 0
(-2200 1150);
PAINT MONO (-2200 1150);
DISPLAY INVISIBLE (-2200 1150);
FORCEPROP 1 LAST PATH I164
J 0
(-2200 1100);
DISPLAY 0.978723 (-2200 1100);
PAINT WHITE (-2200 1100);
DISPLAY INVISIBLE (-2200 1100);
FORCEPROP 0 LAST ROOM PVCCIN_CPU0_DECAP_VR
J 0
(-2200 1150);
DISPLAY 1.021277 (-2200 1150);
PAINT ORANGE (-2200 1150);
DISPLAY INVISIBLE (-2200 1150);
FORCEADD CAP..1
(-3175 950);
FORCEPROP 1 LAST LOCATION C4P10
J 0
(-3125 1050);
DISPLAY 0.617021 (-3125 1050);
PAINT AQUA (-3125 1050);
FORCEPROP 1 LAST PART_NUMBER C95333-006
R 1
J 0
(-3225 775);
DISPLAY 0.617021 (-3225 775);
PAINT BLUE (-3225 775);
FORCEPROP 1 LAST VALUE 47UF
J 0
(-3125 1000);
DISPLAY 0.617021 (-3125 1000);
PAINT SKYBLUE (-3125 1000);
FORCEPROP 1 LAST TOLERANCE 20%
J 0
(-3125 900);
DISPLAY 0.617021 (-3125 900);
PAINT SKYBLUE (-3125 900);
FORCEPROP 1 LAST PACK_TYPE 0805
J 0
(-3125 800);
DISPLAY 0.617021 (-3125 800);
PAINT SKYBLUE (-3125 800);
FORCEPROP 1 LAST MATERIAL X6S
J 0
(-3125 850);
DISPLAY 0.617021 (-3125 850);
PAINT SKYBLUE (-3125 850);
FORCEPROP 1 LASTPIN (-3175 850) $PN 2
J 0
(-3165 830);
DISPLAY 0.617021 (-3165 830);
PAINT ORANGE (-3165 830);
FORCEPROP 1 LASTPIN (-3175 1050) $PN 1
J 0
(-3165 1030);
DISPLAY 0.617021 (-3165 1030);
PAINT ORANGE (-3165 1030);
FORCEPROP 1 LAST VOLTAGE 4V
J 0
(-3125 950);
PAINT SKYBLUE (-3125 950);
DISPLAY INVISIBLE (-3125 950);
FORCEPROP 2 LAST BOM_COST PROC_SOCKET
J 0
(-3125 1150);
DISPLAY 1.021277 (-3125 1150);
PAINT ORANGE (-3125 1150);
DISPLAY INVISIBLE (-3125 1150);
FORCEPROP 2 LAST CDS_LIB mstr_discrete
J 0
(-3175 950);
PAINT ORANGE (-3175 950);
DISPLAY INVISIBLE (-3175 950);
FORCEPROP 2 LAST CDS_SEC 1
J 0
(-3115 1170);
PAINT MONO (-3115 1170);
DISPLAY INVISIBLE (-3115 1170);
FORCEPROP 2 LAST $SEC 1
J 0
(-3115 1170);
PAINT MONO (-3115 1170);
DISPLAY INVISIBLE (-3115 1170);
FORCEPROP 2 LAST CDS_LOCATION C4P10
J 0
(-3125 1050);
DISPLAY 0.617021 (-3125 1050);
PAINT AQUA (-3125 1050);
DISPLAY INVISIBLE (-3125 1050);
FORCEPROP 1 LAST PATH I17
J 0
(-3125 1100);
DISPLAY 0.978723 (-3125 1100);
PAINT WHITE (-3125 1100);
DISPLAY INVISIBLE (-3125 1100);
FORCEPROP 2 LAST ROOM PVCCIN_CPU0_DECAP_VR
J 0
(-3125 1100);
DISPLAY 1.021277 (-3125 1100);
PAINT ORANGE (-3125 1100);
DISPLAY INVISIBLE (-3125 1100);
FORCEADD CAP..1
(-1400 2150);
FORCEPROP 1 LAST LOCATION C4P5
J 0
(-1350 2250);
DISPLAY 0.617021 (-1350 2250);
PAINT AQUA (-1350 2250);
FORCEPROP 1 LAST PART_NUMBER C95333-006
R 1
J 0
(-1450 2000);
DISPLAY 0.617021 (-1450 2000);
PAINT BLUE (-1450 2000);
FORCEPROP 1 LAST VALUE 47UF
J 0
(-1350 2200);
DISPLAY 0.617021 (-1350 2200);
PAINT SKYBLUE (-1350 2200);
FORCEPROP 1 LAST TOLERANCE 20%
J 0
(-1350 2100);
DISPLAY 0.617021 (-1350 2100);
PAINT SKYBLUE (-1350 2100);
FORCEPROP 1 LAST PACK_TYPE 0805
J 0
(-1350 2000);
DISPLAY 0.617021 (-1350 2000);
PAINT SKYBLUE (-1350 2000);
FORCEPROP 1 LAST VOLTAGE 4V
J 0
(-1350 2150);
DISPLAY 0.617021 (-1350 2150);
PAINT SKYBLUE (-1350 2150);
FORCEPROP 1 LAST MATERIAL X6S
J 0
(-1350 2050);
DISPLAY 0.617021 (-1350 2050);
PAINT SKYBLUE (-1350 2050);
FORCEPROP 1 LASTPIN (-1400 2050) $PN 2
J 0
(-1390 2030);
DISPLAY 0.617021 (-1390 2030);
PAINT ORANGE (-1390 2030);
FORCEPROP 1 LASTPIN (-1400 2250) $PN 1
J 0
(-1390 2230);
DISPLAY 0.617021 (-1390 2230);
PAINT ORANGE (-1390 2230);
FORCEPROP 2 LAST CDS_LIB mstr_discrete
J 0
(-1400 2150);
PAINT ORANGE (-1400 2150);
DISPLAY INVISIBLE (-1400 2150);
FORCEPROP 2 LAST CDS_SEC 1
J 0
(-1350 2350);
PAINT MONO (-1350 2350);
DISPLAY INVISIBLE (-1350 2350);
FORCEPROP 2 LAST $SEC 1
J 0
(-1350 2350);
PAINT MONO (-1350 2350);
DISPLAY INVISIBLE (-1350 2350);
FORCEPROP 2 LAST CDS_LOCATION C4P5
J 0
(-1350 2250);
DISPLAY 0.617021 (-1350 2250);
PAINT AQUA (-1350 2250);
DISPLAY INVISIBLE (-1350 2250);
FORCEPROP 1 LAST PATH I172
J 0
(-1350 2300);
DISPLAY 0.978723 (-1350 2300);
PAINT WHITE (-1350 2300);
DISPLAY INVISIBLE (-1350 2300);
FORCEPROP 0 LAST ROOM PVCCIN_CPU0_DECAP_VR
J 0
(-1350 2300);
DISPLAY 1.021277 (-1350 2300);
PAINT ORANGE (-1350 2300);
DISPLAY INVISIBLE (-1350 2300);
FORCEADD CAP_A..1
(-1375 3850);
FORCEPROP 1 LAST LOCATION C5D20
J 0
(-1325 3950);
DISPLAY 0.617021 (-1325 3950);
PAINT AQUA (-1325 3950);
FORCEPROP 1 LAST PART_NUMBER E15431-004
J 0
(-1325 3700);
DISPLAY 0.617021 (-1325 3700);
PAINT BLUE (-1325 3700);
FORCEPROP 1 LAST VALUE 22.0UF
J 0
(-1325 3900);
DISPLAY 0.617021 (-1325 3900);
PAINT SKYBLUE (-1325 3900);
FORCEPROP 1 LAST TOLERANCE 20%
J 0
(-1325 3800);
DISPLAY 0.617021 (-1325 3800);
PAINT SKYBLUE (-1325 3800);
FORCEPROP 1 LAST PACK_TYPE 0603V
J 0
(-1325 3650);
DISPLAY 0.617021 (-1325 3650);
PAINT SKYBLUE (-1325 3650);
FORCEPROP 1 LAST VOLTAGE 4V
J 0
(-1325 3850);
DISPLAY 0.617021 (-1325 3850);
PAINT SKYBLUE (-1325 3850);
FORCEPROP 1 LAST MATERIAL X6S
J 0
(-1325 3750);
DISPLAY 0.617021 (-1325 3750);
PAINT SKYBLUE (-1325 3750);
FORCEPROP 2 LAST CDS_LOCATION C5D20
J 0
(-1325 3950);
DISPLAY 0.617021 (-1325 3950);
PAINT AQUA (-1325 3950);
DISPLAY INVISIBLE (-1325 3950);
FORCEPROP 2 LAST BOM_COST PROC_SOCKET
J 0
(-1325 4050);
DISPLAY 1.021277 (-1325 4050);
PAINT ORANGE (-1325 4050);
DISPLAY INVISIBLE (-1325 4050);
FORCEPROP 2 LAST CDS_LIB dev_discrete
J 0
(-1375 3850);
PAINT ORANGE (-1375 3850);
DISPLAY INVISIBLE (-1375 3850);
FORCEPROP 2 LAST CDS_SEC 1
J 0
(-1325 4050);
PAINT MONO (-1325 4050);
DISPLAY INVISIBLE (-1325 4050);
FORCEPROP 2 LAST $SEC 1
J 0
(-1325 4050);
PAINT MONO (-1325 4050);
DISPLAY INVISIBLE (-1325 4050);
FORCEPROP 1 LAST PATH I173
J 0
(-1325 4000);
DISPLAY 0.978723 (-1325 4000);
PAINT WHITE (-1325 4000);
DISPLAY INVISIBLE (-1325 4000);
FORCEPROP 2 LAST ROOM PVCCIN_CPU0_DECAP_VR
J 0
(-1325 4000);
DISPLAY 1.021277 (-1325 4000);
PAINT ORANGE (-1325 4000);
DISPLAY INVISIBLE (-1325 4000);
FORCEPROP 1 LASTPIN (-1375 3950) $PN 1
J 0
(-1365 3930);
DISPLAY 0.787234 (-1365 3930);
PAINT ORANGE (-1365 3930);
DISPLAY INVISIBLE (-1365 3930);
FORCEPROP 1 LASTPIN (-1375 3750) $PN 2
J 0
(-1365 3730);
DISPLAY 0.787234 (-1365 3730);
PAINT ORANGE (-1365 3730);
DISPLAY INVISIBLE (-1365 3730);
FORCEADD CAP_A..1
(-975 3825);
FORCEPROP 1 LAST LOCATION C5D33
J 0
(-925 3925);
DISPLAY 0.617021 (-925 3925);
PAINT AQUA (-925 3925);
FORCEPROP 1 LAST PART_NUMBER E15431-004
J 0
(-925 3675);
DISPLAY 0.617021 (-925 3675);
PAINT BLUE (-925 3675);
FORCEPROP 1 LAST VALUE 22.0UF
J 0
(-925 3875);
DISPLAY 0.617021 (-925 3875);
PAINT SKYBLUE (-925 3875);
FORCEPROP 1 LAST TOLERANCE 20%
J 0
(-925 3775);
DISPLAY 0.617021 (-925 3775);
PAINT SKYBLUE (-925 3775);
FORCEPROP 1 LAST PACK_TYPE 0603V
J 0
(-925 3625);
DISPLAY 0.617021 (-925 3625);
PAINT SKYBLUE (-925 3625);
FORCEPROP 1 LAST VOLTAGE 4V
J 0
(-925 3825);
DISPLAY 0.617021 (-925 3825);
PAINT SKYBLUE (-925 3825);
FORCEPROP 1 LAST MATERIAL X6S
J 0
(-925 3725);
DISPLAY 0.617021 (-925 3725);
PAINT SKYBLUE (-925 3725);
FORCEPROP 2 LAST CDS_LOCATION C5D33
J 0
(-925 3925);
DISPLAY 0.617021 (-925 3925);
PAINT AQUA (-925 3925);
DISPLAY INVISIBLE (-925 3925);
FORCEPROP 2 LAST BOM_COST PROC_SOCKET
J 0
(-925 4025);
DISPLAY 1.021277 (-925 4025);
PAINT ORANGE (-925 4025);
DISPLAY INVISIBLE (-925 4025);
FORCEPROP 2 LAST CDS_LIB dev_discrete
J 0
(-975 3825);
PAINT ORANGE (-975 3825);
DISPLAY INVISIBLE (-975 3825);
FORCEPROP 2 LAST CDS_SEC 1
J 0
(-925 4025);
PAINT MONO (-925 4025);
DISPLAY INVISIBLE (-925 4025);
FORCEPROP 2 LAST $SEC 1
J 0
(-925 4025);
PAINT MONO (-925 4025);
DISPLAY INVISIBLE (-925 4025);
FORCEPROP 1 LAST PATH I174
J 0
(-925 3975);
DISPLAY 0.978723 (-925 3975);
PAINT WHITE (-925 3975);
DISPLAY INVISIBLE (-925 3975);
FORCEPROP 2 LAST ROOM PVCCIN_CPU0_DECAP_VR
J 0
(-925 3975);
DISPLAY 1.021277 (-925 3975);
PAINT ORANGE (-925 3975);
DISPLAY INVISIBLE (-925 3975);
FORCEPROP 1 LASTPIN (-975 3925) $PN 1
J 0
(-965 3905);
DISPLAY 0.787234 (-965 3905);
PAINT ORANGE (-965 3905);
DISPLAY INVISIBLE (-965 3905);
FORCEPROP 1 LASTPIN (-975 3725) $PN 2
J 0
(-965 3705);
DISPLAY 0.787234 (-965 3705);
PAINT ORANGE (-965 3705);
DISPLAY INVISIBLE (-965 3705);
FORCEADD CAP_A..1
(-600 3800);
FORCEPROP 1 LAST LOCATION C5D34
J 0
(-550 3900);
DISPLAY 0.617021 (-550 3900);
PAINT AQUA (-550 3900);
FORCEPROP 1 LAST PART_NUMBER E15431-004
J 0
(-550 3650);
DISPLAY 0.617021 (-550 3650);
PAINT BLUE (-550 3650);
FORCEPROP 1 LAST VALUE 22.0UF
J 0
(-550 3850);
DISPLAY 0.617021 (-550 3850);
PAINT SKYBLUE (-550 3850);
FORCEPROP 1 LAST TOLERANCE 20%
J 0
(-550 3750);
DISPLAY 0.617021 (-550 3750);
PAINT SKYBLUE (-550 3750);
FORCEPROP 1 LAST PACK_TYPE 0603V
J 0
(-550 3600);
DISPLAY 0.617021 (-550 3600);
PAINT SKYBLUE (-550 3600);
FORCEPROP 1 LAST VOLTAGE 4V
J 0
(-550 3800);
DISPLAY 0.617021 (-550 3800);
PAINT SKYBLUE (-550 3800);
FORCEPROP 1 LAST MATERIAL X6S
J 0
(-550 3700);
DISPLAY 0.617021 (-550 3700);
PAINT SKYBLUE (-550 3700);
FORCEPROP 2 LAST CDS_LOCATION C5D34
J 0
(-550 3900);
DISPLAY 0.617021 (-550 3900);
PAINT AQUA (-550 3900);
DISPLAY INVISIBLE (-550 3900);
FORCEPROP 2 LAST BOM_COST PROC_SOCKET
J 0
(-550 4000);
DISPLAY 1.021277 (-550 4000);
PAINT ORANGE (-550 4000);
DISPLAY INVISIBLE (-550 4000);
FORCEPROP 2 LAST CDS_LIB dev_discrete
J 0
(-600 3800);
PAINT ORANGE (-600 3800);
DISPLAY INVISIBLE (-600 3800);
FORCEPROP 2 LAST CDS_SEC 1
J 0
(-550 4000);
PAINT MONO (-550 4000);
DISPLAY INVISIBLE (-550 4000);
FORCEPROP 2 LAST $SEC 1
J 0
(-550 4000);
PAINT MONO (-550 4000);
DISPLAY INVISIBLE (-550 4000);
FORCEPROP 1 LAST PATH I175
J 0
(-550 3950);
DISPLAY 0.978723 (-550 3950);
PAINT WHITE (-550 3950);
DISPLAY INVISIBLE (-550 3950);
FORCEPROP 2 LAST ROOM PVCCIN_CPU0_DECAP_VR
J 0
(-550 3950);
DISPLAY 1.021277 (-550 3950);
PAINT ORANGE (-550 3950);
DISPLAY INVISIBLE (-550 3950);
FORCEPROP 1 LASTPIN (-600 3900) $PN 1
J 0
(-590 3880);
DISPLAY 0.787234 (-590 3880);
PAINT ORANGE (-590 3880);
DISPLAY INVISIBLE (-590 3880);
FORCEPROP 1 LASTPIN (-600 3700) $PN 2
J 0
(-590 3680);
DISPLAY 0.787234 (-590 3680);
PAINT ORANGE (-590 3680);
DISPLAY INVISIBLE (-590 3680);
FORCEADD CAP_A..1
(-1700 3850);
FORCEPROP 1 LAST LOCATION C5D35
J 0
(-1650 3950);
DISPLAY 0.617021 (-1650 3950);
PAINT AQUA (-1650 3950);
FORCEPROP 1 LAST PART_NUMBER E15431-004
J 0
(-1650 3700);
DISPLAY 0.617021 (-1650 3700);
PAINT BLUE (-1650 3700);
FORCEPROP 1 LAST VALUE 22.0UF
J 0
(-1650 3900);
DISPLAY 0.617021 (-1650 3900);
PAINT SKYBLUE (-1650 3900);
FORCEPROP 1 LAST TOLERANCE 20%
J 0
(-1650 3800);
DISPLAY 0.617021 (-1650 3800);
PAINT SKYBLUE (-1650 3800);
FORCEPROP 1 LAST PACK_TYPE 0603V
J 0
(-1650 3650);
DISPLAY 0.617021 (-1650 3650);
PAINT SKYBLUE (-1650 3650);
FORCEPROP 1 LAST VOLTAGE 4V
J 0
(-1650 3850);
DISPLAY 0.617021 (-1650 3850);
PAINT SKYBLUE (-1650 3850);
FORCEPROP 1 LAST MATERIAL X6S
J 0
(-1650 3750);
DISPLAY 0.617021 (-1650 3750);
PAINT SKYBLUE (-1650 3750);
FORCEPROP 2 LAST CDS_LOCATION C5D35
J 0
(-1650 3950);
DISPLAY 0.617021 (-1650 3950);
PAINT AQUA (-1650 3950);
DISPLAY INVISIBLE (-1650 3950);
FORCEPROP 2 LAST BOM_COST PROC_SOCKET
J 0
(-1650 4050);
DISPLAY 1.021277 (-1650 4050);
PAINT ORANGE (-1650 4050);
DISPLAY INVISIBLE (-1650 4050);
FORCEPROP 2 LAST CDS_LIB dev_discrete
J 0
(-1700 3850);
PAINT ORANGE (-1700 3850);
DISPLAY INVISIBLE (-1700 3850);
FORCEPROP 2 LAST CDS_SEC 1
J 0
(-1650 4050);
PAINT MONO (-1650 4050);
DISPLAY INVISIBLE (-1650 4050);
FORCEPROP 2 LAST $SEC 1
J 0
(-1650 4050);
PAINT MONO (-1650 4050);
DISPLAY INVISIBLE (-1650 4050);
FORCEPROP 1 LAST PATH I176
J 0
(-1650 4000);
DISPLAY 0.978723 (-1650 4000);
PAINT WHITE (-1650 4000);
DISPLAY INVISIBLE (-1650 4000);
FORCEPROP 2 LAST ROOM PVCCIN_CPU0_DECAP_VR
J 0
(-1650 4000);
DISPLAY 1.021277 (-1650 4000);
PAINT ORANGE (-1650 4000);
DISPLAY INVISIBLE (-1650 4000);
FORCEPROP 1 LASTPIN (-1700 3950) $PN 1
J 0
(-1690 3930);
DISPLAY 0.787234 (-1690 3930);
PAINT ORANGE (-1690 3930);
DISPLAY INVISIBLE (-1690 3930);
FORCEPROP 1 LASTPIN (-1700 3750) $PN 2
J 0
(-1690 3730);
DISPLAY 0.787234 (-1690 3730);
PAINT ORANGE (-1690 3730);
DISPLAY INVISIBLE (-1690 3730);
FORCEADD CAP_A..1
(-1950 950);
FORCEPROP 1 LAST LOCATION C4P8
J 0
(-1900 1050);
DISPLAY 0.617021 (-1900 1050);
PAINT AQUA (-1900 1050);
FORCEPROP 1 LAST PART_NUMBER E15431-004
J 0
(-1900 800);
DISPLAY 0.617021 (-1900 800);
PAINT BLUE (-1900 800);
FORCEPROP 1 LAST VALUE 22.0UF
J 0
(-1900 1000);
DISPLAY 0.617021 (-1900 1000);
PAINT SKYBLUE (-1900 1000);
FORCEPROP 1 LAST TOLERANCE 20%
J 0
(-1900 900);
DISPLAY 0.617021 (-1900 900);
PAINT SKYBLUE (-1900 900);
FORCEPROP 1 LAST PACK_TYPE 0603V
J 0
(-1900 750);
DISPLAY 0.617021 (-1900 750);
PAINT SKYBLUE (-1900 750);
FORCEPROP 1 LAST VOLTAGE 4V
J 0
(-1900 950);
DISPLAY 0.617021 (-1900 950);
PAINT SKYBLUE (-1900 950);
FORCEPROP 1 LAST MATERIAL X6S
J 0
(-1900 850);
DISPLAY 0.617021 (-1900 850);
PAINT SKYBLUE (-1900 850);
FORCEPROP 2 LAST CDS_LOCATION C4P8
J 0
(-1900 1050);
DISPLAY 0.617021 (-1900 1050);
PAINT AQUA (-1900 1050);
DISPLAY INVISIBLE (-1900 1050);
FORCEPROP 2 LAST CDS_LIB dev_discrete
J 0
(-1950 950);
PAINT ORANGE (-1950 950);
DISPLAY INVISIBLE (-1950 950);
FORCEPROP 2 LAST CDS_SEC 1
J 0
(-1900 1150);
PAINT MONO (-1900 1150);
DISPLAY INVISIBLE (-1900 1150);
FORCEPROP 2 LAST $SEC 1
J 0
(-1900 1150);
PAINT MONO (-1900 1150);
DISPLAY INVISIBLE (-1900 1150);
FORCEPROP 1 LAST PATH I178
J 0
(-1900 1100);
DISPLAY 0.978723 (-1900 1100);
PAINT WHITE (-1900 1100);
DISPLAY INVISIBLE (-1900 1100);
FORCEPROP 0 LAST ROOM PVCCIN_CPU0_DECAP_VR
J 0
(-1900 1100);
DISPLAY 1.021277 (-1900 1100);
PAINT ORANGE (-1900 1100);
DISPLAY INVISIBLE (-1900 1100);
FORCEPROP 1 LASTPIN (-1950 1050) $PN 1
J 0
(-1940 1030);
DISPLAY 0.787234 (-1940 1030);
PAINT ORANGE (-1940 1030);
DISPLAY INVISIBLE (-1940 1030);
FORCEPROP 1 LASTPIN (-1950 850) $PN 2
J 0
(-1940 830);
DISPLAY 0.787234 (-1940 830);
PAINT ORANGE (-1940 830);
DISPLAY INVISIBLE (-1940 830);
FORCEADD CAP_A..1
(-2150 3850);
FORCEPROP 1 LAST LOCATION C5D53
J 0
(-2100 3950);
DISPLAY 0.617021 (-2100 3950);
PAINT AQUA (-2100 3950);
FORCEPROP 1 LAST PART_NUMBER E15431-004
J 0
(-2100 3700);
DISPLAY 0.617021 (-2100 3700);
PAINT BLUE (-2100 3700);
FORCEPROP 1 LAST VALUE 22.0UF
J 0
(-2100 3900);
DISPLAY 0.617021 (-2100 3900);
PAINT SKYBLUE (-2100 3900);
FORCEPROP 1 LAST TOLERANCE 20%
J 0
(-2100 3800);
DISPLAY 0.617021 (-2100 3800);
PAINT SKYBLUE (-2100 3800);
FORCEPROP 1 LAST PACK_TYPE 0603V
J 0
(-2100 3650);
DISPLAY 0.617021 (-2100 3650);
PAINT SKYBLUE (-2100 3650);
FORCEPROP 1 LAST VOLTAGE 4V
J 0
(-2100 3850);
DISPLAY 0.617021 (-2100 3850);
PAINT SKYBLUE (-2100 3850);
FORCEPROP 1 LAST MATERIAL X6S
J 0
(-2100 3750);
DISPLAY 0.617021 (-2100 3750);
PAINT SKYBLUE (-2100 3750);
FORCEPROP 2 LAST CDS_LOCATION C5D53
J 0
(-2100 3950);
DISPLAY 0.617021 (-2100 3950);
PAINT AQUA (-2100 3950);
DISPLAY INVISIBLE (-2100 3950);
FORCEPROP 2 LAST CDS_LIB dev_discrete
J 0
(-2150 3850);
PAINT ORANGE (-2150 3850);
DISPLAY INVISIBLE (-2150 3850);
FORCEPROP 2 LAST CDS_SEC 1
J 0
(-2100 4050);
PAINT MONO (-2100 4050);
DISPLAY INVISIBLE (-2100 4050);
FORCEPROP 2 LAST $SEC 1
J 0
(-2100 4050);
PAINT MONO (-2100 4050);
DISPLAY INVISIBLE (-2100 4050);
FORCEPROP 1 LAST PATH I179
J 0
(-2100 4000);
DISPLAY 0.978723 (-2100 4000);
PAINT WHITE (-2100 4000);
DISPLAY INVISIBLE (-2100 4000);
FORCEPROP 0 LAST ROOM PVCCIN_CPU0_DECAP_VR
J 0
(-2100 4000);
DISPLAY 1.021277 (-2100 4000);
PAINT ORANGE (-2100 4000);
DISPLAY INVISIBLE (-2100 4000);
FORCEPROP 1 LASTPIN (-2150 3950) $PN 1
J 0
(-2140 3930);
DISPLAY 0.787234 (-2140 3930);
PAINT ORANGE (-2140 3930);
DISPLAY INVISIBLE (-2140 3930);
FORCEPROP 1 LASTPIN (-2150 3750) $PN 2
J 0
(-2140 3730);
DISPLAY 0.787234 (-2140 3730);
PAINT ORANGE (-2140 3730);
DISPLAY INVISIBLE (-2140 3730);
FORCEADD CAP..1
(-3600 975);
FORCEPROP 1 LAST LOCATION C5P9
J 0
(-3550 1075);
DISPLAY 0.617021 (-3550 1075);
PAINT AQUA (-3550 1075);
FORCEPROP 1 LAST PART_NUMBER C95333-002
R 1
J 0
(-3650 800);
DISPLAY 0.617021 (-3650 800);
PAINT BLUE (-3650 800);
FORCEPROP 1 LAST VALUE 22UF
J 0
(-3550 1025);
DISPLAY 0.617021 (-3550 1025);
PAINT SKYBLUE (-3550 1025);
FORCEPROP 1 LAST TOLERANCE 20%
J 0
(-3550 925);
DISPLAY 0.617021 (-3550 925);
PAINT SKYBLUE (-3550 925);
FORCEPROP 1 LAST PACK_TYPE 0805LF
J 0
(-3550 825);
DISPLAY 0.617021 (-3550 825);
PAINT SKYBLUE (-3550 825);
FORCEPROP 1 LASTPIN (-3600 875) $PN 2
J 0
(-3590 855);
DISPLAY 0.617021 (-3590 855);
PAINT GREEN (-3590 855);
FORCEPROP 1 LASTPIN (-3600 1075) $PN 1
J 0
(-3590 1055);
DISPLAY 0.617021 (-3590 1055);
PAINT GREEN (-3590 1055);
FORCEPROP 1 LAST VOLTAGE 4V
J 0
(-3550 975);
PAINT SKYBLUE (-3550 975);
DISPLAY INVISIBLE (-3550 975);
FORCEPROP 1 LAST MATERIAL X6S
J 0
(-3550 875);
PAINT SKYBLUE (-3550 875);
DISPLAY INVISIBLE (-3550 875);
FORCEPROP 2 LAST CDS_LIB mstr_discrete
J 0
(-3600 975);
PAINT ORANGE (-3600 975);
DISPLAY INVISIBLE (-3600 975);
FORCEPROP 2 LAST BOM_COST PROC_SOCKET
J 0
(-3550 1175);
DISPLAY 1.021277 (-3550 1175);
PAINT ORANGE (-3550 1175);
DISPLAY INVISIBLE (-3550 1175);
FORCEPROP 2 LAST CDS_SEC 1
J 0
(-3550 1175);
DISPLAY 1.021277 (-3550 1175);
PAINT ORANGE (-3550 1175);
DISPLAY INVISIBLE (-3550 1175);
FORCEPROP 2 LAST $SEC 1
J 0
(-3550 1175);
DISPLAY 0.680851 (-3550 1175);
PAINT MONO (-3550 1175);
DISPLAY INVISIBLE (-3550 1175);
FORCEPROP 2 LAST CDS_LOCATION C5P9
J 0
(-3550 1075);
DISPLAY 0.617021 (-3550 1075);
PAINT AQUA (-3550 1075);
DISPLAY INVISIBLE (-3550 1075);
FORCEPROP 1 LAST PATH I18
J 0
(-3550 1125);
DISPLAY 0.978723 (-3550 1125);
PAINT WHITE (-3550 1125);
DISPLAY INVISIBLE (-3550 1125);
FORCEPROP 2 LAST ROOM PVCCIN_CPU0_DECAP_VR
J 0
(-3550 1125);
DISPLAY 1.021277 (-3550 1125);
PAINT ORANGE (-3550 1125);
DISPLAY INVISIBLE (-3550 1125);
FORCEADD CAP_A..1
(-2525 3825);
FORCEPROP 1 LAST LOCATION C5D52
J 0
(-2475 3925);
DISPLAY 0.617021 (-2475 3925);
PAINT AQUA (-2475 3925);
FORCEPROP 1 LAST PART_NUMBER E15431-004
J 0
(-2475 3675);
DISPLAY 0.617021 (-2475 3675);
PAINT BLUE (-2475 3675);
FORCEPROP 1 LAST VALUE 22.0UF
J 0
(-2475 3875);
DISPLAY 0.617021 (-2475 3875);
PAINT SKYBLUE (-2475 3875);
FORCEPROP 1 LAST TOLERANCE 20%
J 0
(-2475 3775);
DISPLAY 0.617021 (-2475 3775);
PAINT SKYBLUE (-2475 3775);
FORCEPROP 1 LAST PACK_TYPE 0603V
J 0
(-2475 3625);
DISPLAY 0.617021 (-2475 3625);
PAINT SKYBLUE (-2475 3625);
FORCEPROP 1 LAST VOLTAGE 4V
J 0
(-2475 3825);
DISPLAY 0.617021 (-2475 3825);
PAINT SKYBLUE (-2475 3825);
FORCEPROP 1 LAST MATERIAL X6S
J 0
(-2475 3725);
DISPLAY 0.617021 (-2475 3725);
PAINT SKYBLUE (-2475 3725);
FORCEPROP 2 LAST CDS_LOCATION C5D52
J 0
(-2475 3925);
DISPLAY 0.617021 (-2475 3925);
PAINT AQUA (-2475 3925);
DISPLAY INVISIBLE (-2475 3925);
FORCEPROP 2 LAST CDS_LIB dev_discrete
J 0
(-2525 3825);
PAINT ORANGE (-2525 3825);
DISPLAY INVISIBLE (-2525 3825);
FORCEPROP 2 LAST CDS_SEC 1
J 0
(-2475 4025);
PAINT MONO (-2475 4025);
DISPLAY INVISIBLE (-2475 4025);
FORCEPROP 2 LAST $SEC 1
J 0
(-2475 4025);
PAINT MONO (-2475 4025);
DISPLAY INVISIBLE (-2475 4025);
FORCEPROP 1 LAST PATH I180
J 0
(-2475 3975);
DISPLAY 0.978723 (-2475 3975);
PAINT WHITE (-2475 3975);
DISPLAY INVISIBLE (-2475 3975);
FORCEPROP 0 LAST ROOM PVCCIN_CPU0_DECAP_VR
J 0
(-2475 3975);
DISPLAY 1.021277 (-2475 3975);
PAINT ORANGE (-2475 3975);
DISPLAY INVISIBLE (-2475 3975);
FORCEPROP 1 LASTPIN (-2525 3925) $PN 1
J 0
(-2515 3905);
DISPLAY 0.787234 (-2515 3905);
PAINT ORANGE (-2515 3905);
DISPLAY INVISIBLE (-2515 3905);
FORCEPROP 1 LASTPIN (-2525 3725) $PN 2
J 0
(-2515 3705);
DISPLAY 0.787234 (-2515 3705);
PAINT ORANGE (-2515 3705);
DISPLAY INVISIBLE (-2515 3705);
FORCEADD VCC_CORE..1
(-2525 4125);
FORCEPROP 3 LASTPIN (-2525 4075) SIG_NAME PVCCMCP_CPU0\g
J 0
(-2515 4085);
DISPLAY 0.659574 (-2515 4085);
PAINT MONO (-2515 4085);
DISPLAY INVISIBLE (-2515 4085);
FORCEPROP 1 LAST HDL_POWER PVCCMCP_CPU0
J 1
(-2525 4175);
DISPLAY 0.617021 (-2525 4175);
PAINT GREEN (-2525 4175);
FORCEPROP 2 LAST CDS_LIB mstr_symbols
J 0
(-2525 4125);
PAINT ORANGE (-2525 4125);
DISPLAY INVISIBLE (-2525 4125);
FORCEPROP 1 LAST PATH I181
J 0
(-2475 4150);
DISPLAY 0.872340 (-2475 4150);
PAINT AQUA (-2475 4150);
DISPLAY INVISIBLE (-2475 4150);
FORCEADD GND..1
(-600 3475);
FORCEPROP 3 LASTPIN (-600 3525) SIG_NAME GND\g
J 0
(-590 3535);
DISPLAY 0.659574 (-590 3535);
PAINT MONO (-590 3535);
DISPLAY INVISIBLE (-590 3535);
FORCEPROP 1 LAST VOLTAGE 0
J 0
(-600 3475);
PAINT SKYBLUE (-600 3475);
DISPLAY INVISIBLE (-600 3475);
FORCEPROP 1 LAST SIZE 1B
J 0
(-525 3425);
DISPLAY 0.893617 (-525 3425);
PAINT GREEN (-525 3425);
DISPLAY INVISIBLE (-525 3425);
FORCEPROP 2 LAST CDS_LIB mstr_symbols
J 0
(-600 3475);
PAINT ORANGE (-600 3475);
DISPLAY INVISIBLE (-600 3475);
FORCEPROP 1 LAST BODY_TYPE PLUMBING
J 0
(-645 3432);
DISPLAY 0.340426 (-645 3432);
PAINT GREEN (-645 3432);
DISPLAY INVISIBLE (-645 3432);
FORCEPROP 1 LAST PATH I182
J 0
(-525 3475);
DISPLAY 0.872340 (-525 3475);
PAINT AQUA (-525 3475);
DISPLAY INVISIBLE (-525 3475);
FORCEPROP 1 LAST HDL_POWER GND
J 0
(-600 3625);
DISPLAY 0.893617 (-600 3625);
PAINT GREEN (-600 3625);
DISPLAY INVISIBLE (-600 3625);
FORCEADD CAP..1
(-375 2150);
FORCEPROP 1 LAST LOCATION C5P12
J 0
(-325 2250);
DISPLAY 0.617021 (-325 2250);
PAINT AQUA (-325 2250);
FORCEPROP 1 LAST PART_NUMBER C95333-006
R 1
J 0
(-425 1975);
DISPLAY 0.617021 (-425 1975);
PAINT BLUE (-425 1975);
FORCEPROP 1 LAST VALUE 47UF
J 0
(-325 2200);
DISPLAY 0.617021 (-325 2200);
PAINT SKYBLUE (-325 2200);
FORCEPROP 1 LAST TOLERANCE 20%
J 0
(-325 2100);
DISPLAY 0.617021 (-325 2100);
PAINT SKYBLUE (-325 2100);
FORCEPROP 1 LAST PACK_TYPE 0805
J 0
(-325 2000);
DISPLAY 0.617021 (-325 2000);
PAINT SKYBLUE (-325 2000);
FORCEPROP 1 LAST VOLTAGE 4V
J 0
(-325 2150);
PAINT SKYBLUE (-325 2150);
DISPLAY INVISIBLE (-325 2150);
FORCEPROP 1 LAST MATERIAL X6S
J 0
(-325 2050);
PAINT SKYBLUE (-325 2050);
DISPLAY INVISIBLE (-325 2050);
FORCEPROP 2 LAST BOM_COST PROC_SOCKET
J 0
(-325 2350);
DISPLAY 1.021277 (-325 2350);
PAINT ORANGE (-325 2350);
DISPLAY INVISIBLE (-325 2350);
FORCEPROP 2 LAST CDS_LIB mstr_discrete
J 0
(-375 2150);
PAINT ORANGE (-375 2150);
DISPLAY INVISIBLE (-375 2150);
FORCEPROP 2 LAST CDS_SEC 1
J 0
(-325 2350);
PAINT MONO (-325 2350);
DISPLAY INVISIBLE (-325 2350);
FORCEPROP 2 LAST $SEC 1
J 0
(-325 2350);
PAINT MONO (-325 2350);
DISPLAY INVISIBLE (-325 2350);
FORCEPROP 2 LAST CDS_LOCATION C5P12
J 0
(-325 2250);
DISPLAY 0.617021 (-325 2250);
PAINT AQUA (-325 2250);
DISPLAY INVISIBLE (-325 2250);
FORCEPROP 1 LAST PATH I183
J 0
(-325 2300);
DISPLAY 0.978723 (-325 2300);
PAINT WHITE (-325 2300);
DISPLAY INVISIBLE (-325 2300);
FORCEPROP 2 LAST ROOM PVCCIN_CPU0_DECAP_VR
J 0
(-325 2300);
DISPLAY 1.021277 (-325 2300);
PAINT ORANGE (-325 2300);
DISPLAY INVISIBLE (-325 2300);
FORCEPROP 1 LASTPIN (-375 2050) $PN 2
J 0
(-365 2030);
DISPLAY 0.787234 (-365 2030);
PAINT ORANGE (-365 2030);
DISPLAY INVISIBLE (-365 2030);
FORCEPROP 1 LASTPIN (-375 2250) $PN 1
J 0
(-365 2230);
DISPLAY 0.787234 (-365 2230);
PAINT ORANGE (-365 2230);
DISPLAY INVISIBLE (-365 2230);
FORCEADD CAP..1
(-625 2150);
FORCEPROP 1 LAST LOCATION C5P21
J 0
(-575 2250);
DISPLAY 0.617021 (-575 2250);
PAINT AQUA (-575 2250);
FORCEPROP 1 LAST PART_NUMBER C95333-006
R 1
J 0
(-675 2000);
DISPLAY 0.617021 (-675 2000);
PAINT BLUE (-675 2000);
FORCEPROP 1 LAST VALUE 47UF
J 0
(-575 2200);
DISPLAY 0.617021 (-575 2200);
PAINT SKYBLUE (-575 2200);
FORCEPROP 1 LAST TOLERANCE 20%
J 0
(-575 2100);
DISPLAY 0.617021 (-575 2100);
PAINT SKYBLUE (-575 2100);
FORCEPROP 1 LAST PACK_TYPE 0805
J 0
(-585 2010);
DISPLAY 0.617021 (-585 2010);
PAINT SKYBLUE (-585 2010);
FORCEPROP 1 LAST VOLTAGE 4V
J 0
(-575 2150);
PAINT SKYBLUE (-575 2150);
DISPLAY INVISIBLE (-575 2150);
FORCEPROP 1 LAST MATERIAL X6S
J 0
(-575 2050);
PAINT SKYBLUE (-575 2050);
DISPLAY INVISIBLE (-575 2050);
FORCEPROP 2 LAST BOM_COST PROC_SOCKET
J 0
(-575 2350);
DISPLAY 1.021277 (-575 2350);
PAINT ORANGE (-575 2350);
DISPLAY INVISIBLE (-575 2350);
FORCEPROP 2 LAST CDS_LIB mstr_discrete
J 0
(-625 2150);
PAINT ORANGE (-625 2150);
DISPLAY INVISIBLE (-625 2150);
FORCEPROP 2 LAST CDS_SEC 1
J 0
(-575 2350);
PAINT MONO (-575 2350);
DISPLAY INVISIBLE (-575 2350);
FORCEPROP 2 LAST $SEC 1
J 0
(-575 2350);
PAINT MONO (-575 2350);
DISPLAY INVISIBLE (-575 2350);
FORCEPROP 2 LAST CDS_LOCATION C5P21
J 0
(-575 2250);
DISPLAY 0.617021 (-575 2250);
PAINT AQUA (-575 2250);
DISPLAY INVISIBLE (-575 2250);
FORCEPROP 1 LAST PATH I184
J 0
(-575 2300);
DISPLAY 0.978723 (-575 2300);
PAINT WHITE (-575 2300);
DISPLAY INVISIBLE (-575 2300);
FORCEPROP 2 LAST ROOM PVCCIN_CPU0_DECAP_VR
J 0
(-575 2300);
DISPLAY 1.021277 (-575 2300);
PAINT ORANGE (-575 2300);
DISPLAY INVISIBLE (-575 2300);
FORCEPROP 1 LASTPIN (-625 2050) $PN 2
J 0
(-615 2030);
DISPLAY 0.787234 (-615 2030);
PAINT ORANGE (-615 2030);
DISPLAY INVISIBLE (-615 2030);
FORCEPROP 1 LASTPIN (-625 2250) $PN 1
J 0
(-615 2230);
DISPLAY 0.787234 (-615 2230);
PAINT ORANGE (-615 2230);
DISPLAY INVISIBLE (-615 2230);
FORCEADD CAP..1
(-875 2150);
FORCEPROP 1 LAST LOCATION C5P20
J 0
(-825 2250);
DISPLAY 0.617021 (-825 2250);
PAINT AQUA (-825 2250);
FORCEPROP 1 LAST PART_NUMBER C95333-006
R 1
J 0
(-925 2000);
DISPLAY 0.617021 (-925 2000);
PAINT BLUE (-925 2000);
FORCEPROP 1 LAST VALUE 47UF
J 0
(-825 2200);
DISPLAY 0.617021 (-825 2200);
PAINT SKYBLUE (-825 2200);
FORCEPROP 1 LAST TOLERANCE 20%
J 0
(-825 2100);
DISPLAY 0.617021 (-825 2100);
PAINT SKYBLUE (-825 2100);
FORCEPROP 1 LAST PACK_TYPE 0805
J 0
(-825 2000);
DISPLAY 0.617021 (-825 2000);
PAINT SKYBLUE (-825 2000);
FORCEPROP 1 LAST VOLTAGE 4V
J 0
(-825 2150);
PAINT SKYBLUE (-825 2150);
DISPLAY INVISIBLE (-825 2150);
FORCEPROP 1 LAST MATERIAL X6S
J 0
(-825 2050);
PAINT SKYBLUE (-825 2050);
DISPLAY INVISIBLE (-825 2050);
FORCEPROP 2 LAST BOM_COST PROC_SOCKET
J 0
(-825 2350);
DISPLAY 1.021277 (-825 2350);
PAINT ORANGE (-825 2350);
DISPLAY INVISIBLE (-825 2350);
FORCEPROP 2 LAST CDS_LIB mstr_discrete
J 0
(-875 2150);
PAINT ORANGE (-875 2150);
DISPLAY INVISIBLE (-875 2150);
FORCEPROP 2 LAST CDS_SEC 1
J 0
(-825 2350);
PAINT MONO (-825 2350);
DISPLAY INVISIBLE (-825 2350);
FORCEPROP 2 LAST $SEC 1
J 0
(-825 2350);
PAINT MONO (-825 2350);
DISPLAY INVISIBLE (-825 2350);
FORCEPROP 2 LAST CDS_LOCATION C5P20
J 0
(-825 2250);
DISPLAY 0.617021 (-825 2250);
PAINT AQUA (-825 2250);
DISPLAY INVISIBLE (-825 2250);
FORCEPROP 1 LAST PATH I185
J 0
(-825 2300);
DISPLAY 0.978723 (-825 2300);
PAINT WHITE (-825 2300);
DISPLAY INVISIBLE (-825 2300);
FORCEPROP 2 LAST ROOM PVCCIN_CPU0_DECAP_VR
J 0
(-825 2300);
DISPLAY 1.021277 (-825 2300);
PAINT ORANGE (-825 2300);
DISPLAY INVISIBLE (-825 2300);
FORCEPROP 1 LASTPIN (-875 2050) $PN 2
J 0
(-865 2030);
DISPLAY 0.787234 (-865 2030);
PAINT ORANGE (-865 2030);
DISPLAY INVISIBLE (-865 2030);
FORCEPROP 1 LASTPIN (-875 2250) $PN 1
J 0
(-865 2230);
DISPLAY 0.787234 (-865 2230);
PAINT ORANGE (-865 2230);
DISPLAY INVISIBLE (-865 2230);
FORCEADD CAP..1
(-1125 2150);
FORCEPROP 1 LAST LOCATION C5P13
J 0
(-1075 2250);
DISPLAY 0.617021 (-1075 2250);
PAINT AQUA (-1075 2250);
FORCEPROP 1 LAST PART_NUMBER C95333-006
R 1
J 0
(-1175 1975);
DISPLAY 0.617021 (-1175 1975);
PAINT BLUE (-1175 1975);
FORCEPROP 1 LAST VALUE 47UF
J 0
(-1075 2200);
DISPLAY 0.617021 (-1075 2200);
PAINT SKYBLUE (-1075 2200);
FORCEPROP 1 LAST TOLERANCE 20%
J 0
(-1075 2100);
DISPLAY 0.617021 (-1075 2100);
PAINT SKYBLUE (-1075 2100);
FORCEPROP 1 LAST PACK_TYPE 0805
J 0
(-1075 2000);
DISPLAY 0.617021 (-1075 2000);
PAINT SKYBLUE (-1075 2000);
FORCEPROP 1 LAST VOLTAGE 4V
J 0
(-1075 2150);
PAINT SKYBLUE (-1075 2150);
DISPLAY INVISIBLE (-1075 2150);
FORCEPROP 1 LAST MATERIAL X6S
J 0
(-1075 2050);
PAINT SKYBLUE (-1075 2050);
DISPLAY INVISIBLE (-1075 2050);
FORCEPROP 2 LAST CDS_LIB mstr_discrete
J 0
(-1125 2150);
PAINT ORANGE (-1125 2150);
DISPLAY INVISIBLE (-1125 2150);
FORCEPROP 2 LAST BOM_COST PROC_SOCKET
J 0
(-1075 2350);
DISPLAY 1.021277 (-1075 2350);
PAINT ORANGE (-1075 2350);
DISPLAY INVISIBLE (-1075 2350);
FORCEPROP 2 LAST CDS_SEC 1
J 0
(-1075 2350);
PAINT MONO (-1075 2350);
DISPLAY INVISIBLE (-1075 2350);
FORCEPROP 2 LAST $SEC 1
J 0
(-1075 2350);
PAINT MONO (-1075 2350);
DISPLAY INVISIBLE (-1075 2350);
FORCEPROP 2 LAST CDS_LOCATION C5P13
J 0
(-1075 2250);
DISPLAY 0.617021 (-1075 2250);
PAINT AQUA (-1075 2250);
DISPLAY INVISIBLE (-1075 2250);
FORCEPROP 1 LAST PATH I186
J 0
(-1075 2300);
DISPLAY 0.978723 (-1075 2300);
PAINT WHITE (-1075 2300);
DISPLAY INVISIBLE (-1075 2300);
FORCEPROP 2 LAST ROOM PVCCIN_CPU0_DECAP_VR
J 0
(-1075 2300);
DISPLAY 1.021277 (-1075 2300);
PAINT ORANGE (-1075 2300);
DISPLAY INVISIBLE (-1075 2300);
FORCEPROP 1 LASTPIN (-1125 2050) $PN 2
J 0
(-1115 2030);
DISPLAY 0.787234 (-1115 2030);
PAINT ORANGE (-1115 2030);
DISPLAY INVISIBLE (-1115 2030);
FORCEPROP 1 LASTPIN (-1125 2250) $PN 1
J 0
(-1115 2230);
DISPLAY 0.787234 (-1115 2230);
PAINT ORANGE (-1115 2230);
DISPLAY INVISIBLE (-1115 2230);
FORCEADD CAP..1
(-6700 1575);
FORCEPROP 1 LAST LOCATION C5P15
J 0
(-6650 1675);
DISPLAY 0.617021 (-6650 1675);
PAINT AQUA (-6650 1675);
FORCEPROP 1 LAST PART_NUMBER C95333-006
R 1
J 0
(-6750 1400);
DISPLAY 0.617021 (-6750 1400);
PAINT BLUE (-6750 1400);
FORCEPROP 1 LAST VALUE 47UF
J 0
(-6650 1625);
DISPLAY 0.617021 (-6650 1625);
PAINT SKYBLUE (-6650 1625);
FORCEPROP 1 LAST TOLERANCE 20%
J 0
(-6650 1525);
DISPLAY 0.617021 (-6650 1525);
PAINT SKYBLUE (-6650 1525);
FORCEPROP 1 LAST PACK_TYPE 0805
J 0
(-6650 1425);
DISPLAY 0.617021 (-6650 1425);
PAINT SKYBLUE (-6650 1425);
FORCEPROP 1 LAST VOLTAGE 4V
J 0
(-6650 1575);
PAINT SKYBLUE (-6650 1575);
DISPLAY INVISIBLE (-6650 1575);
FORCEPROP 1 LAST MATERIAL X6S
J 0
(-6650 1475);
PAINT SKYBLUE (-6650 1475);
DISPLAY INVISIBLE (-6650 1475);
FORCEPROP 2 LAST BOM_COST PROC_SOCKET
J 0
(-6650 1775);
DISPLAY 1.021277 (-6650 1775);
PAINT ORANGE (-6650 1775);
DISPLAY INVISIBLE (-6650 1775);
FORCEPROP 2 LAST CDS_LIB mstr_discrete
J 0
(-6700 1575);
PAINT ORANGE (-6700 1575);
DISPLAY INVISIBLE (-6700 1575);
FORCEPROP 2 LAST CDS_SEC 1
J 0
(-6650 1775);
PAINT MONO (-6650 1775);
DISPLAY INVISIBLE (-6650 1775);
FORCEPROP 2 LAST $SEC 1
J 0
(-6650 1775);
PAINT MONO (-6650 1775);
DISPLAY INVISIBLE (-6650 1775);
FORCEPROP 2 LAST CDS_LOCATION C5P15
J 0
(-6650 1675);
DISPLAY 0.617021 (-6650 1675);
PAINT AQUA (-6650 1675);
DISPLAY INVISIBLE (-6650 1675);
FORCEPROP 1 LAST PATH I187
J 0
(-6650 1725);
DISPLAY 0.978723 (-6650 1725);
PAINT WHITE (-6650 1725);
DISPLAY INVISIBLE (-6650 1725);
FORCEPROP 2 LAST ROOM PVCCIN_CPU0_DECAP_VR
J 0
(-6650 1725);
DISPLAY 1.021277 (-6650 1725);
PAINT ORANGE (-6650 1725);
DISPLAY INVISIBLE (-6650 1725);
FORCEPROP 1 LASTPIN (-6700 1475) $PN 2
J 0
(-6690 1455);
DISPLAY 0.787234 (-6690 1455);
PAINT ORANGE (-6690 1455);
DISPLAY INVISIBLE (-6690 1455);
FORCEPROP 1 LASTPIN (-6700 1675) $PN 1
J 0
(-6690 1655);
DISPLAY 0.787234 (-6690 1655);
PAINT ORANGE (-6690 1655);
DISPLAY INVISIBLE (-6690 1655);
FORCEADD CAP..1
(-6700 2225);
FORCEPROP 1 LAST LOCATION C5P16
J 0
(-6650 2325);
DISPLAY 0.617021 (-6650 2325);
PAINT AQUA (-6650 2325);
FORCEPROP 1 LAST PART_NUMBER C95333-006
R 1
J 0
(-6750 2050);
DISPLAY 0.617021 (-6750 2050);
PAINT BLUE (-6750 2050);
FORCEPROP 1 LAST VALUE 47UF
J 0
(-6650 2275);
DISPLAY 0.617021 (-6650 2275);
PAINT SKYBLUE (-6650 2275);
FORCEPROP 1 LAST TOLERANCE 20%
J 0
(-6650 2175);
DISPLAY 0.617021 (-6650 2175);
PAINT SKYBLUE (-6650 2175);
FORCEPROP 1 LAST PACK_TYPE 0805
J 0
(-6650 2075);
DISPLAY 0.617021 (-6650 2075);
PAINT SKYBLUE (-6650 2075);
FORCEPROP 1 LAST VOLTAGE 4V
J 0
(-6650 2225);
PAINT SKYBLUE (-6650 2225);
DISPLAY INVISIBLE (-6650 2225);
FORCEPROP 1 LAST MATERIAL X6S
J 0
(-6650 2125);
PAINT SKYBLUE (-6650 2125);
DISPLAY INVISIBLE (-6650 2125);
FORCEPROP 2 LAST BOM_COST PROC_SOCKET
J 0
(-6650 2425);
DISPLAY 1.021277 (-6650 2425);
PAINT ORANGE (-6650 2425);
DISPLAY INVISIBLE (-6650 2425);
FORCEPROP 2 LAST CDS_LIB mstr_discrete
J 0
(-6700 2225);
PAINT ORANGE (-6700 2225);
DISPLAY INVISIBLE (-6700 2225);
FORCEPROP 2 LAST CDS_SEC 1
J 0
(-6650 2425);
PAINT MONO (-6650 2425);
DISPLAY INVISIBLE (-6650 2425);
FORCEPROP 2 LAST $SEC 1
J 0
(-6650 2425);
PAINT MONO (-6650 2425);
DISPLAY INVISIBLE (-6650 2425);
FORCEPROP 2 LAST CDS_LOCATION C5P16
J 0
(-6650 2325);
DISPLAY 0.617021 (-6650 2325);
PAINT AQUA (-6650 2325);
DISPLAY INVISIBLE (-6650 2325);
FORCEPROP 1 LAST PATH I188
J 0
(-6650 2375);
DISPLAY 0.978723 (-6650 2375);
PAINT WHITE (-6650 2375);
DISPLAY INVISIBLE (-6650 2375);
FORCEPROP 2 LAST ROOM PVCCIN_CPU0_DECAP_VR
J 0
(-6650 2375);
DISPLAY 1.021277 (-6650 2375);
PAINT ORANGE (-6650 2375);
DISPLAY INVISIBLE (-6650 2375);
FORCEPROP 1 LASTPIN (-6700 2125) $PN 2
J 0
(-6690 2105);
DISPLAY 0.787234 (-6690 2105);
PAINT ORANGE (-6690 2105);
DISPLAY INVISIBLE (-6690 2105);
FORCEPROP 1 LASTPIN (-6700 2325) $PN 1
J 0
(-6690 2305);
DISPLAY 0.787234 (-6690 2305);
PAINT ORANGE (-6690 2305);
DISPLAY INVISIBLE (-6690 2305);
FORCEADD CAP..1
(-7725 925);
FORCEPROP 1 LAST LOCATION C5P3
J 0
(-7675 1025);
DISPLAY 0.617021 (-7675 1025);
PAINT AQUA (-7675 1025);
FORCEPROP 1 LAST PART_NUMBER C95333-006
R 1
J 0
(-7775 750);
DISPLAY 0.617021 (-7775 750);
PAINT BLUE (-7775 750);
FORCEPROP 1 LAST VALUE 47UF
J 0
(-7675 975);
DISPLAY 0.617021 (-7675 975);
PAINT SKYBLUE (-7675 975);
FORCEPROP 1 LAST TOLERANCE 20%
J 0
(-7675 875);
DISPLAY 0.617021 (-7675 875);
PAINT SKYBLUE (-7675 875);
FORCEPROP 1 LAST PACK_TYPE 0805
J 0
(-7675 775);
DISPLAY 0.617021 (-7675 775);
PAINT SKYBLUE (-7675 775);
FORCEPROP 1 LAST VOLTAGE 4V
J 0
(-7675 925);
PAINT SKYBLUE (-7675 925);
DISPLAY INVISIBLE (-7675 925);
FORCEPROP 1 LAST MATERIAL X6S
J 0
(-7675 825);
PAINT SKYBLUE (-7675 825);
DISPLAY INVISIBLE (-7675 825);
FORCEPROP 2 LAST BOM_COST PROC_SOCKET
J 0
(-7675 1125);
DISPLAY 1.021277 (-7675 1125);
PAINT ORANGE (-7675 1125);
DISPLAY INVISIBLE (-7675 1125);
FORCEPROP 2 LAST CDS_LIB mstr_discrete
J 0
(-7725 925);
PAINT ORANGE (-7725 925);
DISPLAY INVISIBLE (-7725 925);
FORCEPROP 2 LAST CDS_SEC 1
J 0
(-7675 1125);
PAINT MONO (-7675 1125);
DISPLAY INVISIBLE (-7675 1125);
FORCEPROP 2 LAST $SEC 1
J 0
(-7675 1125);
PAINT MONO (-7675 1125);
DISPLAY INVISIBLE (-7675 1125);
FORCEPROP 2 LAST CDS_LOCATION C5P3
J 0
(-7675 1025);
DISPLAY 0.617021 (-7675 1025);
PAINT AQUA (-7675 1025);
DISPLAY INVISIBLE (-7675 1025);
FORCEPROP 1 LAST PATH I189
J 0
(-7675 1075);
DISPLAY 0.978723 (-7675 1075);
PAINT WHITE (-7675 1075);
DISPLAY INVISIBLE (-7675 1075);
FORCEPROP 2 LAST ROOM PVCCIN_CPU0_DECAP_VR
J 0
(-7675 1075);
DISPLAY 1.021277 (-7675 1075);
PAINT ORANGE (-7675 1075);
DISPLAY INVISIBLE (-7675 1075);
FORCEPROP 1 LASTPIN (-7725 825) $PN 2
J 0
(-7715 805);
DISPLAY 0.787234 (-7715 805);
PAINT ORANGE (-7715 805);
DISPLAY INVISIBLE (-7715 805);
FORCEPROP 1 LASTPIN (-7725 1025) $PN 1
J 0
(-7715 1005);
DISPLAY 0.787234 (-7715 1005);
PAINT ORANGE (-7715 1005);
DISPLAY INVISIBLE (-7715 1005);
FORCEADD CAP..1
(-3925 975);
FORCEPROP 1 LAST LOCATION C5P8
J 0
(-3875 1075);
DISPLAY 0.617021 (-3875 1075);
PAINT AQUA (-3875 1075);
FORCEPROP 1 LAST PART_NUMBER C95333-002
R 1
J 0
(-3975 800);
DISPLAY 0.617021 (-3975 800);
PAINT BLUE (-3975 800);
FORCEPROP 1 LAST VALUE 22UF
J 0
(-3875 1025);
DISPLAY 0.617021 (-3875 1025);
PAINT SKYBLUE (-3875 1025);
FORCEPROP 1 LAST TOLERANCE 20%
J 0
(-3875 925);
DISPLAY 0.617021 (-3875 925);
PAINT SKYBLUE (-3875 925);
FORCEPROP 1 LAST PACK_TYPE 0805LF
J 0
(-3875 825);
DISPLAY 0.617021 (-3875 825);
PAINT SKYBLUE (-3875 825);
FORCEPROP 1 LASTPIN (-3925 875) $PN 2
J 0
(-3915 855);
DISPLAY 0.617021 (-3915 855);
PAINT GREEN (-3915 855);
FORCEPROP 1 LASTPIN (-3925 1075) $PN 1
J 0
(-3915 1055);
DISPLAY 0.617021 (-3915 1055);
PAINT GREEN (-3915 1055);
FORCEPROP 1 LAST VOLTAGE 4V
J 0
(-3875 975);
PAINT SKYBLUE (-3875 975);
DISPLAY INVISIBLE (-3875 975);
FORCEPROP 1 LAST MATERIAL X6S
J 0
(-3875 875);
PAINT SKYBLUE (-3875 875);
DISPLAY INVISIBLE (-3875 875);
FORCEPROP 2 LAST BOM_COST PROC_SOCKET
J 0
(-3875 1175);
DISPLAY 1.021277 (-3875 1175);
PAINT ORANGE (-3875 1175);
DISPLAY INVISIBLE (-3875 1175);
FORCEPROP 2 LAST CDS_LIB mstr_discrete
J 0
(-3925 975);
PAINT ORANGE (-3925 975);
DISPLAY INVISIBLE (-3925 975);
FORCEPROP 2 LAST CDS_SEC 1
J 0
(-3875 1175);
DISPLAY 1.021277 (-3875 1175);
PAINT ORANGE (-3875 1175);
DISPLAY INVISIBLE (-3875 1175);
FORCEPROP 2 LAST $SEC 1
J 0
(-3875 1175);
DISPLAY 0.680851 (-3875 1175);
PAINT MONO (-3875 1175);
DISPLAY INVISIBLE (-3875 1175);
FORCEPROP 2 LAST CDS_LOCATION C5P8
J 0
(-3875 1075);
DISPLAY 0.617021 (-3875 1075);
PAINT AQUA (-3875 1075);
DISPLAY INVISIBLE (-3875 1075);
FORCEPROP 1 LAST PATH I19
J 0
(-3875 1125);
DISPLAY 0.978723 (-3875 1125);
PAINT WHITE (-3875 1125);
DISPLAY INVISIBLE (-3875 1125);
FORCEPROP 2 LAST ROOM PVCCIN_CPU0_DECAP_VR
J 0
(-3875 1125);
DISPLAY 1.021277 (-3875 1125);
PAINT ORANGE (-3875 1125);
DISPLAY INVISIBLE (-3875 1125);
FORCEADD CAP..1
(-6350 1575);
FORCEPROP 1 LAST LOCATION C5P17
J 0
(-6300 1675);
DISPLAY 0.617021 (-6300 1675);
PAINT AQUA (-6300 1675);
FORCEPROP 1 LAST PART_NUMBER C95333-006
R 1
J 0
(-6400 1400);
DISPLAY 0.617021 (-6400 1400);
PAINT BLUE (-6400 1400);
FORCEPROP 1 LAST VALUE 47UF
J 0
(-6300 1625);
DISPLAY 0.617021 (-6300 1625);
PAINT SKYBLUE (-6300 1625);
FORCEPROP 1 LAST TOLERANCE 20%
J 0
(-6300 1525);
DISPLAY 0.617021 (-6300 1525);
PAINT SKYBLUE (-6300 1525);
FORCEPROP 1 LAST PACK_TYPE 0805
J 0
(-6300 1425);
DISPLAY 0.617021 (-6300 1425);
PAINT SKYBLUE (-6300 1425);
FORCEPROP 1 LAST VOLTAGE 4V
J 0
(-6300 1575);
PAINT SKYBLUE (-6300 1575);
DISPLAY INVISIBLE (-6300 1575);
FORCEPROP 1 LAST MATERIAL X6S
J 0
(-6300 1475);
PAINT SKYBLUE (-6300 1475);
DISPLAY INVISIBLE (-6300 1475);
FORCEPROP 2 LAST BOM_COST PROC_SOCKET
J 0
(-6300 1775);
DISPLAY 1.021277 (-6300 1775);
PAINT ORANGE (-6300 1775);
DISPLAY INVISIBLE (-6300 1775);
FORCEPROP 2 LAST CDS_LIB mstr_discrete
J 0
(-6350 1575);
PAINT ORANGE (-6350 1575);
DISPLAY INVISIBLE (-6350 1575);
FORCEPROP 2 LAST CDS_SEC 1
J 0
(-6300 1775);
PAINT MONO (-6300 1775);
DISPLAY INVISIBLE (-6300 1775);
FORCEPROP 2 LAST $SEC 1
J 0
(-6300 1775);
PAINT MONO (-6300 1775);
DISPLAY INVISIBLE (-6300 1775);
FORCEPROP 2 LAST CDS_LOCATION C5P17
J 0
(-6300 1675);
DISPLAY 0.617021 (-6300 1675);
PAINT AQUA (-6300 1675);
DISPLAY INVISIBLE (-6300 1675);
FORCEPROP 1 LAST PATH I190
J 0
(-6300 1725);
DISPLAY 0.978723 (-6300 1725);
PAINT WHITE (-6300 1725);
DISPLAY INVISIBLE (-6300 1725);
FORCEPROP 2 LAST ROOM PVCCIN_CPU0_DECAP_VR
J 0
(-6300 1725);
DISPLAY 1.021277 (-6300 1725);
PAINT ORANGE (-6300 1725);
DISPLAY INVISIBLE (-6300 1725);
FORCEPROP 1 LASTPIN (-6350 1475) $PN 2
J 0
(-6340 1455);
DISPLAY 0.787234 (-6340 1455);
PAINT ORANGE (-6340 1455);
DISPLAY INVISIBLE (-6340 1455);
FORCEPROP 1 LASTPIN (-6350 1675) $PN 1
J 0
(-6340 1655);
DISPLAY 0.787234 (-6340 1655);
PAINT ORANGE (-6340 1655);
DISPLAY INVISIBLE (-6340 1655);
FORCEADD CAP..1
(-2150 2150);
FORCEPROP 1 LAST LOCATION C5P18
J 0
(-2100 2250);
DISPLAY 0.617021 (-2100 2250);
PAINT AQUA (-2100 2250);
FORCEPROP 1 LAST PART_NUMBER C95333-006
R 1
J 0
(-2200 1975);
DISPLAY 0.617021 (-2200 1975);
PAINT BLUE (-2200 1975);
FORCEPROP 1 LAST VALUE 47UF
J 0
(-2100 2200);
DISPLAY 0.617021 (-2100 2200);
PAINT SKYBLUE (-2100 2200);
FORCEPROP 1 LAST TOLERANCE 20%
J 0
(-2100 2100);
DISPLAY 0.617021 (-2100 2100);
PAINT SKYBLUE (-2100 2100);
FORCEPROP 1 LAST PACK_TYPE 0805
J 0
(-2100 2000);
DISPLAY 0.617021 (-2100 2000);
PAINT SKYBLUE (-2100 2000);
FORCEPROP 1 LASTPIN (-2150 2050) $PN 2
J 0
(-2140 2030);
DISPLAY 0.617021 (-2140 2030);
PAINT GREEN (-2140 2030);
FORCEPROP 1 LASTPIN (-2150 2250) $PN 1
J 0
(-2140 2230);
DISPLAY 0.617021 (-2140 2230);
PAINT GREEN (-2140 2230);
FORCEPROP 1 LAST VOLTAGE 4V
J 0
(-2100 2150);
PAINT SKYBLUE (-2100 2150);
DISPLAY INVISIBLE (-2100 2150);
FORCEPROP 1 LAST MATERIAL X6S
J 0
(-2100 2050);
PAINT SKYBLUE (-2100 2050);
DISPLAY INVISIBLE (-2100 2050);
FORCEPROP 2 LAST CDS_LIB mstr_discrete
J 0
(-2150 2150);
PAINT ORANGE (-2150 2150);
DISPLAY INVISIBLE (-2150 2150);
FORCEPROP 2 LAST BOM_COST PROC_SOCKET
J 0
(-2100 2350);
DISPLAY 1.021277 (-2100 2350);
PAINT ORANGE (-2100 2350);
DISPLAY INVISIBLE (-2100 2350);
FORCEPROP 2 LAST CDS_SEC 1
J 0
(-2100 2350);
DISPLAY 1.021277 (-2100 2350);
PAINT ORANGE (-2100 2350);
DISPLAY INVISIBLE (-2100 2350);
FORCEPROP 2 LAST $SEC 1
J 0
(-2100 2350);
DISPLAY 0.680851 (-2100 2350);
PAINT MONO (-2100 2350);
DISPLAY INVISIBLE (-2100 2350);
FORCEPROP 2 LAST CDS_LOCATION C5P18
J 0
(-2100 2250);
DISPLAY 0.617021 (-2100 2250);
PAINT AQUA (-2100 2250);
DISPLAY INVISIBLE (-2100 2250);
FORCEPROP 1 LAST PATH I2
J 0
(-2100 2300);
DISPLAY 0.978723 (-2100 2300);
PAINT WHITE (-2100 2300);
DISPLAY INVISIBLE (-2100 2300);
FORCEPROP 2 LAST ROOM PVCCIN_CPU0_DECAP_VR
J 0
(-2100 2300);
DISPLAY 1.021277 (-2100 2300);
PAINT ORANGE (-2100 2300);
DISPLAY INVISIBLE (-2100 2300);
FORCEADD GND..1
(-1950 625);
FORCEPROP 3 LASTPIN (-1950 675) SIG_NAME GND\g
J 0
(-1940 685);
DISPLAY 0.659574 (-1940 685);
PAINT MONO (-1940 685);
DISPLAY INVISIBLE (-1940 685);
FORCEPROP 1 LAST VOLTAGE 0
J 0
(-1950 625);
PAINT SKYBLUE (-1950 625);
DISPLAY INVISIBLE (-1950 625);
FORCEPROP 1 LAST SIZE 1B
J 0
(-1875 575);
DISPLAY 0.893617 (-1875 575);
PAINT GREEN (-1875 575);
DISPLAY INVISIBLE (-1875 575);
FORCEPROP 2 LAST CDS_LIB mstr_symbols
J 0
(-1950 625);
PAINT ORANGE (-1950 625);
DISPLAY INVISIBLE (-1950 625);
FORCEPROP 1 LAST BODY_TYPE PLUMBING
J 0
(-1995 582);
DISPLAY 0.340426 (-1995 582);
PAINT GREEN (-1995 582);
DISPLAY INVISIBLE (-1995 582);
FORCEPROP 1 LAST PATH I20
J 0
(-1875 625);
DISPLAY 0.872340 (-1875 625);
PAINT AQUA (-1875 625);
DISPLAY INVISIBLE (-1875 625);
FORCEPROP 1 LAST HDL_POWER GND
J 0
(-1950 775);
DISPLAY 0.893617 (-1950 775);
PAINT GREEN (-1950 775);
DISPLAY INVISIBLE (-1950 775);
FORCEADD GND..1
(-3600 650);
FORCEPROP 3 LASTPIN (-3600 700) SIG_NAME GND\g
J 0
(-3590 710);
DISPLAY 0.659574 (-3590 710);
PAINT MONO (-3590 710);
DISPLAY INVISIBLE (-3590 710);
FORCEPROP 1 LAST VOLTAGE 0
J 0
(-3600 650);
PAINT SKYBLUE (-3600 650);
DISPLAY INVISIBLE (-3600 650);
FORCEPROP 2 LAST CDS_LIB mstr_symbols
J 0
(-3600 650);
PAINT MONO (-3600 650);
DISPLAY INVISIBLE (-3600 650);
FORCEPROP 1 LAST SIZE 1B
J 0
(-3525 600);
DISPLAY 0.893617 (-3525 600);
PAINT GREEN (-3525 600);
DISPLAY INVISIBLE (-3525 600);
FORCEPROP 1 LAST BODY_TYPE PLUMBING
J 0
(-3645 607);
DISPLAY 0.340426 (-3645 607);
PAINT GREEN (-3645 607);
DISPLAY INVISIBLE (-3645 607);
FORCEPROP 1 LAST PATH I21
J 0
(-3525 650);
DISPLAY 0.872340 (-3525 650);
PAINT AQUA (-3525 650);
DISPLAY INVISIBLE (-3525 650);
FORCEPROP 1 LAST HDL_POWER GND
J 0
(-3600 800);
DISPLAY 0.893617 (-3600 800);
PAINT GREEN (-3600 800);
DISPLAY INVISIBLE (-3600 800);
FORCEADD PVSA_CPU0..1
(-4275 1250);
FORCEPROP 3 LASTPIN (-4275 1200) SIG_NAME PVSA_CPU0\g
J 0
(-4265 1210);
DISPLAY 0.659574 (-4265 1210);
PAINT MONO (-4265 1210);
DISPLAY INVISIBLE (-4265 1210);
FORCEPROP 1 LAST VOLTAGE 1.1V
J 0
(-4320 1207);
DISPLAY 0.340426 (-4320 1207);
PAINT SKYBLUE (-4320 1207);
DISPLAY INVISIBLE (-4320 1207);
FORCEPROP 2 LAST CDS_LIB mstr_symbols
J 0
(-4275 1250);
PAINT ORANGE (-4275 1250);
DISPLAY INVISIBLE (-4275 1250);
FORCEPROP 1 LAST BODY_TYPE PLUMBING
J 0
(-4320 1207);
DISPLAY 0.340426 (-4320 1207);
PAINT GREEN (-4320 1207);
DISPLAY INVISIBLE (-4320 1207);
FORCEPROP 1 LAST PATH I24
J 0
(-4225 1275);
DISPLAY 0.872340 (-4225 1275);
PAINT AQUA (-4225 1275);
DISPLAY INVISIBLE (-4225 1275);
FORCEPROP 1 LAST HDL_POWER PVSA_CPU0
J 1
(-4275 1300);
DISPLAY 0.872340 (-4275 1300);
PAINT GREEN (-4275 1300);
DISPLAY INVISIBLE (-4275 1300);
FORCEADD CAP..1
(-4275 975);
FORCEPROP 1 LAST LOCATION C5P7
J 0
(-4225 1075);
DISPLAY 0.617021 (-4225 1075);
PAINT AQUA (-4225 1075);
FORCEPROP 1 LAST PART_NUMBER C95333-002
R 1
J 0
(-4325 800);
DISPLAY 0.617021 (-4325 800);
PAINT BLUE (-4325 800);
FORCEPROP 1 LAST VALUE 22UF
J 0
(-4225 1025);
DISPLAY 0.617021 (-4225 1025);
PAINT SKYBLUE (-4225 1025);
FORCEPROP 1 LAST TOLERANCE 20%
J 0
(-4225 925);
DISPLAY 0.617021 (-4225 925);
PAINT SKYBLUE (-4225 925);
FORCEPROP 1 LAST PACK_TYPE 0805LF
J 0
(-4225 825);
DISPLAY 0.617021 (-4225 825);
PAINT SKYBLUE (-4225 825);
FORCEPROP 1 LASTPIN (-4275 875) $PN 2
J 0
(-4265 855);
DISPLAY 0.617021 (-4265 855);
PAINT GREEN (-4265 855);
FORCEPROP 1 LASTPIN (-4275 1075) $PN 1
J 0
(-4265 1055);
DISPLAY 0.617021 (-4265 1055);
PAINT GREEN (-4265 1055);
FORCEPROP 1 LAST VOLTAGE 4V
J 0
(-4225 975);
PAINT SKYBLUE (-4225 975);
DISPLAY INVISIBLE (-4225 975);
FORCEPROP 1 LAST MATERIAL X6S
J 0
(-4225 875);
PAINT SKYBLUE (-4225 875);
DISPLAY INVISIBLE (-4225 875);
FORCEPROP 2 LAST CDS_LIB mstr_discrete
J 0
(-4275 975);
PAINT ORANGE (-4275 975);
DISPLAY INVISIBLE (-4275 975);
FORCEPROP 2 LAST BOM_COST PROC_SOCKET
J 0
(-4225 1175);
DISPLAY 1.021277 (-4225 1175);
PAINT ORANGE (-4225 1175);
DISPLAY INVISIBLE (-4225 1175);
FORCEPROP 2 LAST CDS_SEC 1
J 0
(-4225 1175);
DISPLAY 1.021277 (-4225 1175);
PAINT ORANGE (-4225 1175);
DISPLAY INVISIBLE (-4225 1175);
FORCEPROP 2 LAST $SEC 1
J 0
(-4225 1175);
DISPLAY 0.680851 (-4225 1175);
PAINT MONO (-4225 1175);
DISPLAY INVISIBLE (-4225 1175);
FORCEPROP 2 LAST CDS_LOCATION C5P7
J 0
(-4225 1075);
DISPLAY 0.617021 (-4225 1075);
PAINT AQUA (-4225 1075);
DISPLAY INVISIBLE (-4225 1075);
FORCEPROP 1 LAST PATH I25
J 0
(-4225 1125);
DISPLAY 0.978723 (-4225 1125);
PAINT WHITE (-4225 1125);
DISPLAY INVISIBLE (-4225 1125);
FORCEPROP 2 LAST ROOM PVCCIN_CPU0_DECAP_VR
J 0
(-4225 1125);
DISPLAY 1.021277 (-4225 1125);
PAINT ORANGE (-4225 1125);
DISPLAY INVISIBLE (-4225 1125);
FORCEADD CAP..1
(-5100 2200);
FORCEPROP 1 LAST LOCATION C5P4
J 0
(-5050 2300);
DISPLAY 0.617021 (-5050 2300);
PAINT AQUA (-5050 2300);
FORCEPROP 1 LAST PART_NUMBER C95333-006
J 0
(-5050 2100);
DISPLAY 0.617021 (-5050 2100);
PAINT BLUE (-5050 2100);
FORCEPROP 1 LAST VALUE 47UF
J 0
(-5050 2250);
DISPLAY 0.617021 (-5050 2250);
PAINT SKYBLUE (-5050 2250);
FORCEPROP 1 LAST TOLERANCE 20%
J 0
(-5050 2150);
DISPLAY 0.617021 (-5050 2150);
PAINT SKYBLUE (-5050 2150);
FORCEPROP 1 LAST PACK_TYPE 0805
J 0
(-5050 2050);
DISPLAY 0.617021 (-5050 2050);
PAINT SKYBLUE (-5050 2050);
FORCEPROP 1 LASTPIN (-5100 2100) $PN 2
J 0
(-5090 2080);
DISPLAY 0.617021 (-5090 2080);
PAINT GREEN (-5090 2080);
FORCEPROP 1 LASTPIN (-5100 2300) $PN 1
J 0
(-5090 2280);
DISPLAY 0.617021 (-5090 2280);
PAINT GREEN (-5090 2280);
FORCEPROP 1 LAST VOLTAGE 4V
J 0
(-5050 2200);
PAINT SKYBLUE (-5050 2200);
DISPLAY INVISIBLE (-5050 2200);
FORCEPROP 1 LAST MATERIAL X6S
J 0
(-5050 2100);
PAINT SKYBLUE (-5050 2100);
DISPLAY INVISIBLE (-5050 2100);
FORCEPROP 2 LAST BOM_COST PROC_SOCKET
J 0
(-5050 2400);
DISPLAY 1.021277 (-5050 2400);
PAINT ORANGE (-5050 2400);
DISPLAY INVISIBLE (-5050 2400);
FORCEPROP 2 LAST CDS_LIB mstr_discrete
J 0
(-5100 2200);
PAINT ORANGE (-5100 2200);
DISPLAY INVISIBLE (-5100 2200);
FORCEPROP 2 LAST CDS_SEC 1
J 0
(-5050 2400);
DISPLAY 1.021277 (-5050 2400);
PAINT ORANGE (-5050 2400);
DISPLAY INVISIBLE (-5050 2400);
FORCEPROP 2 LAST $SEC 1
J 0
(-5050 2400);
DISPLAY 0.680851 (-5050 2400);
PAINT MONO (-5050 2400);
DISPLAY INVISIBLE (-5050 2400);
FORCEPROP 2 LAST CDS_LOCATION C5P4
J 0
(-5050 2300);
DISPLAY 0.617021 (-5050 2300);
PAINT AQUA (-5050 2300);
DISPLAY INVISIBLE (-5050 2300);
FORCEPROP 1 LAST PATH I27
J 0
(-5050 2350);
DISPLAY 0.978723 (-5050 2350);
PAINT WHITE (-5050 2350);
DISPLAY INVISIBLE (-5050 2350);
FORCEPROP 2 LAST ROOM PVCCIN_CPU0_DECAP_VR
J 0
(-5050 2350);
DISPLAY 1.021277 (-5050 2350);
PAINT ORANGE (-5050 2350);
DISPLAY INVISIBLE (-5050 2350);
FORCEADD CAP..1
(-5350 2225);
FORCEPROP 1 LAST LOCATION C5P23
J 0
(-5300 2325);
DISPLAY 0.617021 (-5300 2325);
PAINT AQUA (-5300 2325);
FORCEPROP 1 LAST PART_NUMBER C95333-006
R 1
J 0
(-5400 2050);
DISPLAY 0.617021 (-5400 2050);
PAINT BLUE (-5400 2050);
FORCEPROP 1 LAST VALUE 47UF
J 0
(-5300 2275);
DISPLAY 0.617021 (-5300 2275);
PAINT SKYBLUE (-5300 2275);
FORCEPROP 1 LAST TOLERANCE 20%
J 0
(-5300 2175);
DISPLAY 0.617021 (-5300 2175);
PAINT SKYBLUE (-5300 2175);
FORCEPROP 1 LAST PACK_TYPE 0805
J 0
(-5300 2075);
DISPLAY 0.617021 (-5300 2075);
PAINT SKYBLUE (-5300 2075);
FORCEPROP 1 LASTPIN (-5350 2125) $PN 2
J 0
(-5340 2105);
DISPLAY 0.617021 (-5340 2105);
PAINT GREEN (-5340 2105);
FORCEPROP 1 LASTPIN (-5350 2325) $PN 1
J 0
(-5340 2305);
DISPLAY 0.617021 (-5340 2305);
PAINT GREEN (-5340 2305);
FORCEPROP 1 LAST VOLTAGE 4V
J 0
(-5300 2225);
PAINT SKYBLUE (-5300 2225);
DISPLAY INVISIBLE (-5300 2225);
FORCEPROP 1 LAST MATERIAL X6S
J 0
(-5300 2125);
PAINT SKYBLUE (-5300 2125);
DISPLAY INVISIBLE (-5300 2125);
FORCEPROP 2 LAST CDS_LIB mstr_discrete
J 0
(-5350 2225);
PAINT ORANGE (-5350 2225);
DISPLAY INVISIBLE (-5350 2225);
FORCEPROP 2 LAST BOM_COST PROC_SOCKET
J 0
(-5300 2425);
DISPLAY 1.021277 (-5300 2425);
PAINT ORANGE (-5300 2425);
DISPLAY INVISIBLE (-5300 2425);
FORCEPROP 2 LAST CDS_SEC 1
J 0
(-5300 2425);
DISPLAY 1.021277 (-5300 2425);
PAINT ORANGE (-5300 2425);
DISPLAY INVISIBLE (-5300 2425);
FORCEPROP 2 LAST $SEC 1
J 0
(-5300 2425);
DISPLAY 0.680851 (-5300 2425);
PAINT MONO (-5300 2425);
DISPLAY INVISIBLE (-5300 2425);
FORCEPROP 2 LAST CDS_LOCATION C5P23
J 0
(-5300 2325);
DISPLAY 0.617021 (-5300 2325);
PAINT AQUA (-5300 2325);
DISPLAY INVISIBLE (-5300 2325);
FORCEPROP 1 LAST PATH I28
J 0
(-5300 2375);
DISPLAY 0.978723 (-5300 2375);
PAINT WHITE (-5300 2375);
DISPLAY INVISIBLE (-5300 2375);
FORCEPROP 2 LAST ROOM PVCCIN_CPU0_DECAP_VR
J 0
(-5300 2375);
DISPLAY 1.021277 (-5300 2375);
PAINT ORANGE (-5300 2375);
DISPLAY INVISIBLE (-5300 2375);
FORCEADD GND..1
(-5100 1875);
FORCEPROP 3 LASTPIN (-5100 1925) SIG_NAME GND\g
J 0
(-5090 1935);
DISPLAY 0.659574 (-5090 1935);
PAINT MONO (-5090 1935);
DISPLAY INVISIBLE (-5090 1935);
FORCEPROP 1 LAST VOLTAGE 0
J 0
(-5100 1875);
PAINT SKYBLUE (-5100 1875);
DISPLAY INVISIBLE (-5100 1875);
FORCEPROP 1 LAST SIZE 1B
J 0
(-5025 1825);
DISPLAY 0.893617 (-5025 1825);
PAINT GREEN (-5025 1825);
DISPLAY INVISIBLE (-5025 1825);
FORCEPROP 2 LAST CDS_LIB mstr_symbols
J 0
(-5100 1875);
PAINT ORANGE (-5100 1875);
DISPLAY INVISIBLE (-5100 1875);
FORCEPROP 1 LAST BODY_TYPE PLUMBING
J 0
(-5145 1832);
DISPLAY 0.340426 (-5145 1832);
PAINT GREEN (-5145 1832);
DISPLAY INVISIBLE (-5145 1832);
FORCEPROP 1 LAST PATH I29
J 0
(-5025 1875);
DISPLAY 0.872340 (-5025 1875);
PAINT AQUA (-5025 1875);
DISPLAY INVISIBLE (-5025 1875);
FORCEPROP 1 LAST HDL_POWER GND
J 0
(-5100 2025);
DISPLAY 0.893617 (-5100 2025);
PAINT GREEN (-5100 2025);
DISPLAY INVISIBLE (-5100 2025);
FORCEADD CAP..1
(-2425 2175);
FORCEPROP 1 LAST LOCATION C5P28
J 0
(-2375 2275);
DISPLAY 0.617021 (-2375 2275);
PAINT AQUA (-2375 2275);
FORCEPROP 1 LAST PART_NUMBER C95333-006
R 1
J 0
(-2475 2000);
DISPLAY 0.617021 (-2475 2000);
PAINT BLUE (-2475 2000);
FORCEPROP 1 LAST VALUE 47UF
J 0
(-2375 2225);
DISPLAY 0.617021 (-2375 2225);
PAINT SKYBLUE (-2375 2225);
FORCEPROP 1 LAST TOLERANCE 20%
J 0
(-2375 2125);
DISPLAY 0.617021 (-2375 2125);
PAINT SKYBLUE (-2375 2125);
FORCEPROP 1 LAST PACK_TYPE 0805
J 0
(-2375 2025);
DISPLAY 0.617021 (-2375 2025);
PAINT SKYBLUE (-2375 2025);
FORCEPROP 1 LASTPIN (-2425 2075) $PN 2
J 0
(-2415 2055);
DISPLAY 0.617021 (-2415 2055);
PAINT GREEN (-2415 2055);
FORCEPROP 1 LASTPIN (-2425 2275) $PN 1
J 0
(-2415 2255);
DISPLAY 0.617021 (-2415 2255);
PAINT GREEN (-2415 2255);
FORCEPROP 1 LAST VOLTAGE 4V
J 0
(-2375 2175);
PAINT SKYBLUE (-2375 2175);
DISPLAY INVISIBLE (-2375 2175);
FORCEPROP 1 LAST MATERIAL X6S
J 0
(-2375 2075);
PAINT SKYBLUE (-2375 2075);
DISPLAY INVISIBLE (-2375 2075);
FORCEPROP 2 LAST CDS_LIB mstr_discrete
J 0
(-2425 2175);
PAINT ORANGE (-2425 2175);
DISPLAY INVISIBLE (-2425 2175);
FORCEPROP 2 LAST BOM_COST PROC_SOCKET
J 0
(-2375 2375);
DISPLAY 1.021277 (-2375 2375);
PAINT ORANGE (-2375 2375);
DISPLAY INVISIBLE (-2375 2375);
FORCEPROP 2 LAST CDS_SEC 1
J 0
(-2375 2375);
DISPLAY 1.021277 (-2375 2375);
PAINT ORANGE (-2375 2375);
DISPLAY INVISIBLE (-2375 2375);
FORCEPROP 2 LAST $SEC 1
J 0
(-2375 2375);
DISPLAY 0.680851 (-2375 2375);
PAINT MONO (-2375 2375);
DISPLAY INVISIBLE (-2375 2375);
FORCEPROP 2 LAST CDS_LOCATION C5P28
J 0
(-2375 2275);
DISPLAY 0.617021 (-2375 2275);
PAINT AQUA (-2375 2275);
DISPLAY INVISIBLE (-2375 2275);
FORCEPROP 1 LAST PATH I3
J 0
(-2375 2325);
DISPLAY 0.978723 (-2375 2325);
PAINT WHITE (-2375 2325);
DISPLAY INVISIBLE (-2375 2325);
FORCEPROP 2 LAST ROOM PVCCIN_CPU0_DECAP_VR
J 0
(-2375 2325);
DISPLAY 1.021277 (-2375 2325);
PAINT ORANGE (-2375 2325);
DISPLAY INVISIBLE (-2375 2325);
FORCEADD GND..1
(-5300 1225);
FORCEPROP 3 LASTPIN (-5300 1275) SIG_NAME GND\g
J 0
(-5290 1285);
DISPLAY 0.659574 (-5290 1285);
PAINT MONO (-5290 1285);
DISPLAY INVISIBLE (-5290 1285);
FORCEPROP 1 LAST VOLTAGE 0
J 0
(-5300 1225);
PAINT SKYBLUE (-5300 1225);
DISPLAY INVISIBLE (-5300 1225);
FORCEPROP 2 LAST CDS_LIB mstr_symbols
J 0
(-5300 1225);
PAINT ORANGE (-5300 1225);
DISPLAY INVISIBLE (-5300 1225);
FORCEPROP 1 LAST SIZE 1B
J 0
(-5225 1175);
DISPLAY 0.893617 (-5225 1175);
PAINT GREEN (-5225 1175);
DISPLAY INVISIBLE (-5225 1175);
FORCEPROP 1 LAST BODY_TYPE PLUMBING
J 0
(-5345 1182);
DISPLAY 0.340426 (-5345 1182);
PAINT GREEN (-5345 1182);
DISPLAY INVISIBLE (-5345 1182);
FORCEPROP 1 LAST PATH I32
J 0
(-5225 1225);
DISPLAY 0.872340 (-5225 1225);
PAINT AQUA (-5225 1225);
DISPLAY INVISIBLE (-5225 1225);
FORCEPROP 1 LAST HDL_POWER GND
J 0
(-5300 1375);
DISPLAY 0.893617 (-5300 1375);
PAINT GREEN (-5300 1375);
DISPLAY INVISIBLE (-5300 1375);
FORCEADD CAP..1
(-5300 1575);
FORCEPROP 1 LAST LOCATION C5P24
J 0
(-5250 1675);
DISPLAY 0.617021 (-5250 1675);
PAINT AQUA (-5250 1675);
FORCEPROP 1 LAST PART_NUMBER C95333-006
R 1
J 0
(-5350 1400);
DISPLAY 0.617021 (-5350 1400);
PAINT BLUE (-5350 1400);
FORCEPROP 1 LAST VALUE 47UF
J 0
(-5250 1625);
DISPLAY 0.617021 (-5250 1625);
PAINT SKYBLUE (-5250 1625);
FORCEPROP 1 LAST TOLERANCE 20%
J 0
(-5250 1525);
DISPLAY 0.617021 (-5250 1525);
PAINT SKYBLUE (-5250 1525);
FORCEPROP 1 LAST PACK_TYPE 0805
J 0
(-5250 1425);
DISPLAY 0.617021 (-5250 1425);
PAINT SKYBLUE (-5250 1425);
FORCEPROP 1 LASTPIN (-5300 1475) $PN 2
J 0
(-5290 1455);
DISPLAY 0.617021 (-5290 1455);
PAINT GREEN (-5290 1455);
FORCEPROP 1 LASTPIN (-5300 1675) $PN 1
J 0
(-5290 1655);
DISPLAY 0.617021 (-5290 1655);
PAINT GREEN (-5290 1655);
FORCEPROP 1 LAST VOLTAGE 4V
J 0
(-5250 1575);
PAINT SKYBLUE (-5250 1575);
DISPLAY INVISIBLE (-5250 1575);
FORCEPROP 1 LAST MATERIAL X6S
J 0
(-5250 1475);
PAINT SKYBLUE (-5250 1475);
DISPLAY INVISIBLE (-5250 1475);
FORCEPROP 2 LAST CDS_LIB mstr_discrete
J 0
(-5300 1575);
PAINT ORANGE (-5300 1575);
DISPLAY INVISIBLE (-5300 1575);
FORCEPROP 2 LAST BOM_COST PROC_SOCKET
J 0
(-5250 1775);
DISPLAY 1.021277 (-5250 1775);
PAINT ORANGE (-5250 1775);
DISPLAY INVISIBLE (-5250 1775);
FORCEPROP 2 LAST CDS_SEC 1
J 0
(-5250 1775);
DISPLAY 1.021277 (-5250 1775);
PAINT ORANGE (-5250 1775);
DISPLAY INVISIBLE (-5250 1775);
FORCEPROP 2 LAST $SEC 1
J 0
(-5250 1775);
DISPLAY 0.680851 (-5250 1775);
PAINT MONO (-5250 1775);
DISPLAY INVISIBLE (-5250 1775);
FORCEPROP 2 LAST CDS_LOCATION C5P24
J 0
(-5250 1675);
DISPLAY 0.617021 (-5250 1675);
PAINT AQUA (-5250 1675);
DISPLAY INVISIBLE (-5250 1675);
FORCEPROP 1 LAST PATH I33
J 0
(-5250 1725);
DISPLAY 0.978723 (-5250 1725);
PAINT WHITE (-5250 1725);
DISPLAY INVISIBLE (-5250 1725);
FORCEPROP 2 LAST ROOM PVCCIN_CPU0_DECAP_VR
J 0
(-5250 1725);
DISPLAY 1.021277 (-5250 1725);
PAINT ORANGE (-5250 1725);
DISPLAY INVISIBLE (-5250 1725);
FORCEADD GND..1
(-5275 600);
FORCEPROP 3 LASTPIN (-5275 650) SIG_NAME GND\g
J 0
(-5265 660);
DISPLAY 0.659574 (-5265 660);
PAINT MONO (-5265 660);
DISPLAY INVISIBLE (-5265 660);
FORCEPROP 1 LAST VOLTAGE 0
J 0
(-5275 600);
PAINT SKYBLUE (-5275 600);
DISPLAY INVISIBLE (-5275 600);
FORCEPROP 1 LAST SIZE 1B
J 0
(-5200 550);
DISPLAY 0.893617 (-5200 550);
PAINT GREEN (-5200 550);
DISPLAY INVISIBLE (-5200 550);
FORCEPROP 2 LAST CDS_LIB mstr_symbols
J 0
(-5275 600);
PAINT ORANGE (-5275 600);
DISPLAY INVISIBLE (-5275 600);
FORCEPROP 1 LAST BODY_TYPE PLUMBING
J 0
(-5320 557);
DISPLAY 0.340426 (-5320 557);
PAINT GREEN (-5320 557);
DISPLAY INVISIBLE (-5320 557);
FORCEPROP 1 LAST PATH I35
J 0
(-5200 600);
DISPLAY 0.872340 (-5200 600);
PAINT AQUA (-5200 600);
DISPLAY INVISIBLE (-5200 600);
FORCEPROP 1 LAST HDL_POWER GND
J 0
(-5275 750);
DISPLAY 0.893617 (-5275 750);
PAINT GREEN (-5275 750);
DISPLAY INVISIBLE (-5275 750);
FORCEADD CAP..1
(-5275 900);
FORCEPROP 1 LAST LOCATION C5P25
J 0
(-5225 1000);
DISPLAY 0.617021 (-5225 1000);
PAINT AQUA (-5225 1000);
FORCEPROP 1 LAST PART_NUMBER C95333-006
R 1
J 0
(-5325 725);
DISPLAY 0.617021 (-5325 725);
PAINT BLUE (-5325 725);
FORCEPROP 1 LAST VALUE 47UF
J 0
(-5225 950);
DISPLAY 0.617021 (-5225 950);
PAINT SKYBLUE (-5225 950);
FORCEPROP 1 LAST TOLERANCE 20%
J 0
(-5225 850);
DISPLAY 0.617021 (-5225 850);
PAINT SKYBLUE (-5225 850);
FORCEPROP 1 LAST PACK_TYPE 0805
J 0
(-5225 750);
DISPLAY 0.617021 (-5225 750);
PAINT SKYBLUE (-5225 750);
FORCEPROP 1 LASTPIN (-5275 800) $PN 2
J 0
(-5265 780);
DISPLAY 0.617021 (-5265 780);
PAINT GREEN (-5265 780);
FORCEPROP 1 LASTPIN (-5275 1000) $PN 1
J 0
(-5265 980);
DISPLAY 0.617021 (-5265 980);
PAINT GREEN (-5265 980);
FORCEPROP 1 LAST VOLTAGE 4V
J 0
(-5225 900);
PAINT SKYBLUE (-5225 900);
DISPLAY INVISIBLE (-5225 900);
FORCEPROP 1 LAST MATERIAL X6S
J 0
(-5225 800);
PAINT SKYBLUE (-5225 800);
DISPLAY INVISIBLE (-5225 800);
FORCEPROP 2 LAST BOM_COST PROC_SOCKET
J 0
(-5225 1100);
DISPLAY 1.021277 (-5225 1100);
PAINT ORANGE (-5225 1100);
DISPLAY INVISIBLE (-5225 1100);
FORCEPROP 2 LAST CDS_LIB mstr_discrete
J 0
(-5275 900);
PAINT ORANGE (-5275 900);
DISPLAY INVISIBLE (-5275 900);
FORCEPROP 2 LAST CDS_SEC 1
J 0
(-5225 1100);
DISPLAY 1.021277 (-5225 1100);
PAINT ORANGE (-5225 1100);
DISPLAY INVISIBLE (-5225 1100);
FORCEPROP 2 LAST $SEC 1
J 0
(-5225 1100);
DISPLAY 0.680851 (-5225 1100);
PAINT MONO (-5225 1100);
DISPLAY INVISIBLE (-5225 1100);
FORCEPROP 2 LAST CDS_LOCATION C5P25
J 0
(-5225 1000);
DISPLAY 0.617021 (-5225 1000);
PAINT AQUA (-5225 1000);
DISPLAY INVISIBLE (-5225 1000);
FORCEPROP 1 LAST PATH I37
J 0
(-5225 1050);
DISPLAY 0.978723 (-5225 1050);
PAINT WHITE (-5225 1050);
DISPLAY INVISIBLE (-5225 1050);
FORCEPROP 2 LAST ROOM PVCCIN_CPU0_DECAP_VR
J 0
(-5225 1050);
DISPLAY 1.021277 (-5225 1050);
PAINT ORANGE (-5225 1050);
DISPLAY INVISIBLE (-5225 1050);
FORCEADD CAP..1
(-5675 2225);
FORCEPROP 1 LAST LOCATION C5P6
J 0
(-5625 2325);
DISPLAY 0.617021 (-5625 2325);
PAINT AQUA (-5625 2325);
FORCEPROP 1 LAST PART_NUMBER C95333-006
J 0
(-5625 2125);
DISPLAY 0.617021 (-5625 2125);
PAINT BLUE (-5625 2125);
FORCEPROP 1 LAST VALUE 47UF
J 0
(-5625 2275);
DISPLAY 0.617021 (-5625 2275);
PAINT SKYBLUE (-5625 2275);
FORCEPROP 1 LAST TOLERANCE 20%
J 0
(-5625 2175);
DISPLAY 0.617021 (-5625 2175);
PAINT SKYBLUE (-5625 2175);
FORCEPROP 1 LAST PACK_TYPE 0805
J 0
(-5625 2075);
DISPLAY 0.617021 (-5625 2075);
PAINT SKYBLUE (-5625 2075);
FORCEPROP 1 LASTPIN (-5675 2125) $PN 2
J 0
(-5665 2105);
DISPLAY 0.617021 (-5665 2105);
PAINT GREEN (-5665 2105);
FORCEPROP 1 LASTPIN (-5675 2325) $PN 1
J 0
(-5665 2305);
DISPLAY 0.617021 (-5665 2305);
PAINT GREEN (-5665 2305);
FORCEPROP 1 LAST VOLTAGE 4V
J 0
(-5625 2225);
PAINT SKYBLUE (-5625 2225);
DISPLAY INVISIBLE (-5625 2225);
FORCEPROP 1 LAST MATERIAL X6S
J 0
(-5625 2125);
PAINT SKYBLUE (-5625 2125);
DISPLAY INVISIBLE (-5625 2125);
FORCEPROP 2 LAST CDS_LIB mstr_discrete
J 0
(-5675 2225);
PAINT ORANGE (-5675 2225);
DISPLAY INVISIBLE (-5675 2225);
FORCEPROP 2 LAST BOM_COST PROC_SOCKET
J 0
(-5625 2425);
DISPLAY 1.021277 (-5625 2425);
PAINT ORANGE (-5625 2425);
DISPLAY INVISIBLE (-5625 2425);
FORCEPROP 2 LAST CDS_SEC 1
J 0
(-5625 2425);
DISPLAY 1.021277 (-5625 2425);
PAINT ORANGE (-5625 2425);
DISPLAY INVISIBLE (-5625 2425);
FORCEPROP 2 LAST $SEC 1
J 0
(-5625 2425);
DISPLAY 0.680851 (-5625 2425);
PAINT MONO (-5625 2425);
DISPLAY INVISIBLE (-5625 2425);
FORCEPROP 2 LAST CDS_LOCATION C5P6
J 0
(-5625 2325);
DISPLAY 0.617021 (-5625 2325);
PAINT AQUA (-5625 2325);
DISPLAY INVISIBLE (-5625 2325);
FORCEPROP 1 LAST PATH I38
J 0
(-5625 2375);
DISPLAY 0.978723 (-5625 2375);
PAINT WHITE (-5625 2375);
DISPLAY INVISIBLE (-5625 2375);
FORCEPROP 2 LAST ROOM PVCCIN_CPU0_DECAP_VR
J 0
(-5625 2375);
DISPLAY 1.021277 (-5625 2375);
PAINT ORANGE (-5625 2375);
DISPLAY INVISIBLE (-5625 2375);
FORCEADD PVCCIN_CPU0..1
(-5975 2500);
FORCEPROP 3 LASTPIN (-5975 2450) SIG_NAME PVCCIN_CPU0\g
J 0
(-5965 2460);
DISPLAY 0.659574 (-5965 2460);
PAINT MONO (-5965 2460);
DISPLAY INVISIBLE (-5965 2460);
FORCEPROP 1 LAST VOLTAGE 2.0V
J 0
(-6020 2457);
DISPLAY 0.340426 (-6020 2457);
PAINT SKYBLUE (-6020 2457);
DISPLAY INVISIBLE (-6020 2457);
FORCEPROP 2 LAST CDS_LIB mstr_symbols
J 0
(-5975 2500);
PAINT ORANGE (-5975 2500);
DISPLAY INVISIBLE (-5975 2500);
FORCEPROP 1 LAST BODY_TYPE PLUMBING
J 0
(-6020 2457);
DISPLAY 0.340426 (-6020 2457);
PAINT GREEN (-6020 2457);
DISPLAY INVISIBLE (-6020 2457);
FORCEPROP 1 LAST PATH I39
J 0
(-5925 2525);
DISPLAY 0.872340 (-5925 2525);
PAINT AQUA (-5925 2525);
DISPLAY INVISIBLE (-5925 2525);
FORCEPROP 1 LAST HDL_POWER PVCCIN_CPU0
J 1
(-5975 2550);
DISPLAY 0.872340 (-5975 2550);
PAINT GREEN (-5975 2550);
DISPLAY INVISIBLE (-5975 2550);
FORCEADD CAP..1
(-2700 2175);
FORCEPROP 1 LAST LOCATION C5P11
J 0
(-2650 2275);
DISPLAY 0.617021 (-2650 2275);
PAINT AQUA (-2650 2275);
FORCEPROP 1 LAST PART_NUMBER C95333-006
R 1
J 0
(-2750 2000);
DISPLAY 0.617021 (-2750 2000);
PAINT BLUE (-2750 2000);
FORCEPROP 1 LAST VALUE 47UF
J 0
(-2650 2225);
DISPLAY 0.617021 (-2650 2225);
PAINT SKYBLUE (-2650 2225);
FORCEPROP 1 LAST TOLERANCE 20%
J 0
(-2650 2125);
DISPLAY 0.617021 (-2650 2125);
PAINT SKYBLUE (-2650 2125);
FORCEPROP 1 LAST PACK_TYPE 0805
J 0
(-2650 2025);
DISPLAY 0.617021 (-2650 2025);
PAINT SKYBLUE (-2650 2025);
FORCEPROP 1 LASTPIN (-2700 2075) $PN 2
J 0
(-2690 2055);
DISPLAY 0.617021 (-2690 2055);
PAINT GREEN (-2690 2055);
FORCEPROP 1 LASTPIN (-2700 2275) $PN 1
J 0
(-2690 2255);
DISPLAY 0.617021 (-2690 2255);
PAINT GREEN (-2690 2255);
FORCEPROP 1 LAST VOLTAGE 4V
J 0
(-2650 2175);
PAINT SKYBLUE (-2650 2175);
DISPLAY INVISIBLE (-2650 2175);
FORCEPROP 1 LAST MATERIAL X6S
J 0
(-2650 2075);
PAINT SKYBLUE (-2650 2075);
DISPLAY INVISIBLE (-2650 2075);
FORCEPROP 2 LAST CDS_LIB mstr_discrete
J 0
(-2700 2175);
PAINT ORANGE (-2700 2175);
DISPLAY INVISIBLE (-2700 2175);
FORCEPROP 2 LAST BOM_COST PROC_SOCKET
J 0
(-2650 2375);
DISPLAY 1.021277 (-2650 2375);
PAINT ORANGE (-2650 2375);
DISPLAY INVISIBLE (-2650 2375);
FORCEPROP 2 LAST CDS_SEC 1
J 0
(-2650 2375);
DISPLAY 1.021277 (-2650 2375);
PAINT ORANGE (-2650 2375);
DISPLAY INVISIBLE (-2650 2375);
FORCEPROP 2 LAST $SEC 1
J 0
(-2650 2375);
DISPLAY 0.680851 (-2650 2375);
PAINT MONO (-2650 2375);
DISPLAY INVISIBLE (-2650 2375);
FORCEPROP 2 LAST CDS_LOCATION C5P11
J 0
(-2650 2275);
DISPLAY 0.617021 (-2650 2275);
PAINT AQUA (-2650 2275);
DISPLAY INVISIBLE (-2650 2275);
FORCEPROP 1 LAST PATH I4
J 0
(-2650 2325);
DISPLAY 0.978723 (-2650 2325);
PAINT WHITE (-2650 2325);
DISPLAY INVISIBLE (-2650 2325);
FORCEPROP 2 LAST ROOM PVCCIN_CPU0_DECAP_VR
J 0
(-2650 2325);
DISPLAY 1.021277 (-2650 2325);
PAINT ORANGE (-2650 2325);
DISPLAY INVISIBLE (-2650 2325);
FORCEADD CAP..1
(-5975 2225);
FORCEPROP 1 LAST LOCATION C5P41
J 0
(-5925 2325);
DISPLAY 0.617021 (-5925 2325);
PAINT AQUA (-5925 2325);
FORCEPROP 1 LAST PART_NUMBER C95333-006
J 0
(-5925 2125);
DISPLAY 0.617021 (-5925 2125);
PAINT BLUE (-5925 2125);
FORCEPROP 1 LAST VALUE 47UF
J 0
(-5925 2275);
DISPLAY 0.617021 (-5925 2275);
PAINT SKYBLUE (-5925 2275);
FORCEPROP 1 LAST TOLERANCE 20%
J 0
(-5925 2175);
DISPLAY 0.617021 (-5925 2175);
PAINT SKYBLUE (-5925 2175);
FORCEPROP 1 LAST PACK_TYPE 0805
J 0
(-5925 2075);
DISPLAY 0.617021 (-5925 2075);
PAINT SKYBLUE (-5925 2075);
FORCEPROP 1 LASTPIN (-5975 2125) $PN 2
J 0
(-5965 2105);
DISPLAY 0.617021 (-5965 2105);
PAINT GREEN (-5965 2105);
FORCEPROP 1 LASTPIN (-5975 2325) $PN 1
J 0
(-5965 2305);
DISPLAY 0.617021 (-5965 2305);
PAINT GREEN (-5965 2305);
FORCEPROP 1 LAST VOLTAGE 4V
J 0
(-5925 2225);
PAINT SKYBLUE (-5925 2225);
DISPLAY INVISIBLE (-5925 2225);
FORCEPROP 1 LAST MATERIAL X6S
J 0
(-5925 2125);
PAINT SKYBLUE (-5925 2125);
DISPLAY INVISIBLE (-5925 2125);
FORCEPROP 2 LAST CDS_LIB mstr_discrete
J 0
(-5975 2225);
PAINT ORANGE (-5975 2225);
DISPLAY INVISIBLE (-5975 2225);
FORCEPROP 2 LAST BOM_COST PROC_SOCKET
J 0
(-5925 2425);
DISPLAY 1.021277 (-5925 2425);
PAINT ORANGE (-5925 2425);
DISPLAY INVISIBLE (-5925 2425);
FORCEPROP 2 LAST CDS_SEC 1
J 0
(-5925 2425);
DISPLAY 1.021277 (-5925 2425);
PAINT ORANGE (-5925 2425);
DISPLAY INVISIBLE (-5925 2425);
FORCEPROP 2 LAST $SEC 1
J 0
(-5925 2425);
DISPLAY 0.680851 (-5925 2425);
PAINT MONO (-5925 2425);
DISPLAY INVISIBLE (-5925 2425);
FORCEPROP 2 LAST CDS_LOCATION C5P41
J 0
(-5925 2325);
DISPLAY 0.617021 (-5925 2325);
PAINT AQUA (-5925 2325);
DISPLAY INVISIBLE (-5925 2325);
FORCEPROP 1 LAST PATH I40
J 0
(-5925 2375);
DISPLAY 0.978723 (-5925 2375);
PAINT WHITE (-5925 2375);
DISPLAY INVISIBLE (-5925 2375);
FORCEPROP 2 LAST ROOM PVCCIN_CPU0_DECAP_VR
J 0
(-5925 2375);
DISPLAY 1.021277 (-5925 2375);
PAINT ORANGE (-5925 2375);
DISPLAY INVISIBLE (-5925 2375);
FORCEADD CAP..1
(-6350 2225);
FORCEPROP 1 LAST LOCATION C5P14
J 0
(-6300 2325);
DISPLAY 0.617021 (-6300 2325);
PAINT AQUA (-6300 2325);
FORCEPROP 1 LAST PART_NUMBER C95333-006
J 0
(-6300 2125);
DISPLAY 0.617021 (-6300 2125);
PAINT BLUE (-6300 2125);
FORCEPROP 1 LAST VALUE 47UF
J 0
(-6300 2275);
DISPLAY 0.617021 (-6300 2275);
PAINT SKYBLUE (-6300 2275);
FORCEPROP 1 LAST TOLERANCE 20%
J 0
(-6300 2175);
DISPLAY 0.617021 (-6300 2175);
PAINT SKYBLUE (-6300 2175);
FORCEPROP 1 LAST PACK_TYPE 0805
J 0
(-6300 2075);
DISPLAY 0.617021 (-6300 2075);
PAINT SKYBLUE (-6300 2075);
FORCEPROP 1 LASTPIN (-6350 2125) $PN 2
J 0
(-6340 2105);
DISPLAY 0.617021 (-6340 2105);
PAINT GREEN (-6340 2105);
FORCEPROP 1 LASTPIN (-6350 2325) $PN 1
J 0
(-6340 2305);
DISPLAY 0.617021 (-6340 2305);
PAINT GREEN (-6340 2305);
FORCEPROP 1 LAST VOLTAGE 4V
J 0
(-6300 2225);
PAINT SKYBLUE (-6300 2225);
DISPLAY INVISIBLE (-6300 2225);
FORCEPROP 1 LAST MATERIAL X6S
J 0
(-6300 2125);
PAINT SKYBLUE (-6300 2125);
DISPLAY INVISIBLE (-6300 2125);
FORCEPROP 2 LAST BOM_COST PROC_SOCKET
J 0
(-6300 2425);
DISPLAY 1.021277 (-6300 2425);
PAINT ORANGE (-6300 2425);
DISPLAY INVISIBLE (-6300 2425);
FORCEPROP 2 LAST CDS_LIB mstr_discrete
J 0
(-6350 2225);
PAINT ORANGE (-6350 2225);
DISPLAY INVISIBLE (-6350 2225);
FORCEPROP 2 LAST CDS_SEC 1
J 0
(-6300 2425);
PAINT MONO (-6300 2425);
DISPLAY INVISIBLE (-6300 2425);
FORCEPROP 2 LAST $SEC 1
J 0
(-6300 2425);
PAINT MONO (-6300 2425);
DISPLAY INVISIBLE (-6300 2425);
FORCEPROP 2 LAST CDS_LOCATION C5P14
J 0
(-6300 2325);
DISPLAY 0.617021 (-6300 2325);
PAINT AQUA (-6300 2325);
DISPLAY INVISIBLE (-6300 2325);
FORCEPROP 1 LAST PATH I41
J 0
(-6300 2375);
DISPLAY 0.978723 (-6300 2375);
PAINT WHITE (-6300 2375);
DISPLAY INVISIBLE (-6300 2375);
FORCEPROP 2 LAST ROOM PVCCIN_CPU0_DECAP_VR
J 0
(-6300 2375);
DISPLAY 1.021277 (-6300 2375);
PAINT ORANGE (-6300 2375);
DISPLAY INVISIBLE (-6300 2375);
FORCEADD CAP..1
(-5625 1575);
FORCEPROP 1 LAST LOCATION C5P5
J 0
(-5575 1675);
DISPLAY 0.617021 (-5575 1675);
PAINT AQUA (-5575 1675);
FORCEPROP 1 LAST PART_NUMBER C95333-006
R 1
J 0
(-5675 1400);
DISPLAY 0.617021 (-5675 1400);
PAINT BLUE (-5675 1400);
FORCEPROP 1 LAST VALUE 47UF
J 0
(-5575 1625);
DISPLAY 0.617021 (-5575 1625);
PAINT SKYBLUE (-5575 1625);
FORCEPROP 1 LAST TOLERANCE 20%
J 0
(-5575 1525);
DISPLAY 0.617021 (-5575 1525);
PAINT SKYBLUE (-5575 1525);
FORCEPROP 1 LAST PACK_TYPE 0805
J 0
(-5575 1425);
DISPLAY 0.617021 (-5575 1425);
PAINT SKYBLUE (-5575 1425);
FORCEPROP 1 LASTPIN (-5625 1475) $PN 2
J 0
(-5615 1455);
DISPLAY 0.617021 (-5615 1455);
PAINT GREEN (-5615 1455);
FORCEPROP 1 LASTPIN (-5625 1675) $PN 1
J 0
(-5615 1655);
DISPLAY 0.617021 (-5615 1655);
PAINT GREEN (-5615 1655);
FORCEPROP 1 LAST VOLTAGE 4V
J 0
(-5575 1575);
PAINT SKYBLUE (-5575 1575);
DISPLAY INVISIBLE (-5575 1575);
FORCEPROP 1 LAST MATERIAL X6S
J 0
(-5575 1475);
PAINT SKYBLUE (-5575 1475);
DISPLAY INVISIBLE (-5575 1475);
FORCEPROP 2 LAST CDS_LIB mstr_discrete
J 0
(-5625 1575);
PAINT ORANGE (-5625 1575);
DISPLAY INVISIBLE (-5625 1575);
FORCEPROP 2 LAST BOM_COST PROC_SOCKET
J 0
(-5575 1775);
DISPLAY 1.021277 (-5575 1775);
PAINT ORANGE (-5575 1775);
DISPLAY INVISIBLE (-5575 1775);
FORCEPROP 2 LAST CDS_SEC 1
J 0
(-5575 1775);
DISPLAY 1.021277 (-5575 1775);
PAINT ORANGE (-5575 1775);
DISPLAY INVISIBLE (-5575 1775);
FORCEPROP 2 LAST $SEC 1
J 0
(-5575 1775);
DISPLAY 0.680851 (-5575 1775);
PAINT MONO (-5575 1775);
DISPLAY INVISIBLE (-5575 1775);
FORCEPROP 2 LAST CDS_LOCATION C5P5
J 0
(-5575 1675);
DISPLAY 0.617021 (-5575 1675);
PAINT AQUA (-5575 1675);
DISPLAY INVISIBLE (-5575 1675);
FORCEPROP 1 LAST PATH I42
J 0
(-5575 1725);
DISPLAY 0.978723 (-5575 1725);
PAINT WHITE (-5575 1725);
DISPLAY INVISIBLE (-5575 1725);
FORCEPROP 2 LAST ROOM PVCCIN_CPU0_DECAP_VR
J 0
(-5575 1725);
DISPLAY 1.021277 (-5575 1725);
PAINT ORANGE (-5575 1725);
DISPLAY INVISIBLE (-5575 1725);
FORCEADD PVCCIN_CPU0..1
(-5975 1850);
FORCEPROP 3 LASTPIN (-5975 1800) SIG_NAME PVCCIN_CPU0\g
J 0
(-5965 1810);
DISPLAY 0.659574 (-5965 1810);
PAINT MONO (-5965 1810);
DISPLAY INVISIBLE (-5965 1810);
FORCEPROP 1 LAST VOLTAGE 2.0V
J 0
(-6020 1807);
DISPLAY 0.340426 (-6020 1807);
PAINT SKYBLUE (-6020 1807);
DISPLAY INVISIBLE (-6020 1807);
FORCEPROP 2 LAST CDS_LIB mstr_symbols
J 0
(-5975 1850);
PAINT ORANGE (-5975 1850);
DISPLAY INVISIBLE (-5975 1850);
FORCEPROP 1 LAST BODY_TYPE PLUMBING
J 0
(-6020 1807);
DISPLAY 0.340426 (-6020 1807);
PAINT GREEN (-6020 1807);
DISPLAY INVISIBLE (-6020 1807);
FORCEPROP 1 LAST PATH I43
J 0
(-5925 1875);
DISPLAY 0.872340 (-5925 1875);
PAINT AQUA (-5925 1875);
DISPLAY INVISIBLE (-5925 1875);
FORCEPROP 1 LAST HDL_POWER PVCCIN_CPU0
J 1
(-5975 1900);
DISPLAY 0.872340 (-5975 1900);
PAINT GREEN (-5975 1900);
DISPLAY INVISIBLE (-5975 1900);
FORCEADD CAP..1
(-5975 1575);
FORCEPROP 1 LAST PART_NUMBER C95333-006
R 1
J 0
(-6025 1400);
DISPLAY 0.617021 (-6025 1400);
PAINT BLUE (-6025 1400);
FORCEPROP 1 LAST LOCATION C5P27
J 0
(-5925 1675);
DISPLAY 0.617021 (-5925 1675);
PAINT AQUA (-5925 1675);
FORCEPROP 1 LAST VALUE 47UF
J 0
(-5925 1625);
DISPLAY 0.617021 (-5925 1625);
PAINT SKYBLUE (-5925 1625);
FORCEPROP 1 LAST TOLERANCE 20%
J 0
(-5925 1525);
DISPLAY 0.617021 (-5925 1525);
PAINT SKYBLUE (-5925 1525);
FORCEPROP 1 LAST PACK_TYPE 0805
J 0
(-5925 1425);
DISPLAY 0.617021 (-5925 1425);
PAINT SKYBLUE (-5925 1425);
FORCEPROP 1 LASTPIN (-5975 1475) $PN 2
J 0
(-5965 1455);
DISPLAY 0.617021 (-5965 1455);
PAINT GREEN (-5965 1455);
FORCEPROP 1 LASTPIN (-5975 1675) $PN 1
J 0
(-5965 1655);
DISPLAY 0.617021 (-5965 1655);
PAINT GREEN (-5965 1655);
FORCEPROP 1 LAST VOLTAGE 4V
J 0
(-5925 1575);
PAINT SKYBLUE (-5925 1575);
DISPLAY INVISIBLE (-5925 1575);
FORCEPROP 1 LAST MATERIAL X6S
J 0
(-5925 1475);
PAINT SKYBLUE (-5925 1475);
DISPLAY INVISIBLE (-5925 1475);
FORCEPROP 2 LAST CDS_LIB mstr_discrete
J 0
(-5975 1575);
PAINT ORANGE (-5975 1575);
DISPLAY INVISIBLE (-5975 1575);
FORCEPROP 2 LAST BOM_COST PROC_SOCKET
J 0
(-5925 1775);
DISPLAY 1.021277 (-5925 1775);
PAINT ORANGE (-5925 1775);
DISPLAY INVISIBLE (-5925 1775);
FORCEPROP 2 LAST CDS_SEC 1
J 0
(-5925 1775);
DISPLAY 1.021277 (-5925 1775);
PAINT ORANGE (-5925 1775);
DISPLAY INVISIBLE (-5925 1775);
FORCEPROP 2 LAST $SEC 1
J 0
(-5925 1775);
DISPLAY 0.680851 (-5925 1775);
PAINT MONO (-5925 1775);
DISPLAY INVISIBLE (-5925 1775);
FORCEPROP 2 LAST CDS_LOCATION C5P27
J 0
(-5925 1675);
DISPLAY 0.617021 (-5925 1675);
PAINT AQUA (-5925 1675);
DISPLAY INVISIBLE (-5925 1675);
FORCEPROP 1 LAST PATH I44
J 0
(-5925 1725);
DISPLAY 0.978723 (-5925 1725);
PAINT WHITE (-5925 1725);
DISPLAY INVISIBLE (-5925 1725);
FORCEPROP 2 LAST ROOM PVCCIN_CPU0_DECAP_VR
J 0
(-5925 1725);
DISPLAY 1.021277 (-5925 1725);
PAINT ORANGE (-5925 1725);
DISPLAY INVISIBLE (-5925 1725);
FORCEADD PVCCIN_CPU0..1
(-5950 1175);
FORCEPROP 3 LASTPIN (-5950 1125) SIG_NAME PVCCIN_CPU0\g
J 0
(-5940 1135);
DISPLAY 0.659574 (-5940 1135);
PAINT MONO (-5940 1135);
DISPLAY INVISIBLE (-5940 1135);
FORCEPROP 1 LAST VOLTAGE 2.0V
J 0
(-5995 1132);
DISPLAY 0.340426 (-5995 1132);
PAINT SKYBLUE (-5995 1132);
DISPLAY INVISIBLE (-5995 1132);
FORCEPROP 2 LAST CDS_LIB mstr_symbols
J 0
(-5950 1175);
PAINT ORANGE (-5950 1175);
DISPLAY INVISIBLE (-5950 1175);
FORCEPROP 1 LAST BODY_TYPE PLUMBING
J 0
(-5995 1132);
DISPLAY 0.340426 (-5995 1132);
PAINT GREEN (-5995 1132);
DISPLAY INVISIBLE (-5995 1132);
FORCEPROP 1 LAST PATH I45
J 0
(-5900 1200);
DISPLAY 0.872340 (-5900 1200);
PAINT AQUA (-5900 1200);
DISPLAY INVISIBLE (-5900 1200);
FORCEPROP 1 LAST HDL_POWER PVCCIN_CPU0
J 1
(-5950 1225);
DISPLAY 0.872340 (-5950 1225);
PAINT GREEN (-5950 1225);
DISPLAY INVISIBLE (-5950 1225);
FORCEADD GND..1
(-6350 1900);
FORCEPROP 3 LASTPIN (-6350 1950) SIG_NAME GND\g
J 0
(-6340 1960);
DISPLAY 0.659574 (-6340 1960);
PAINT MONO (-6340 1960);
DISPLAY INVISIBLE (-6340 1960);
FORCEPROP 1 LAST VOLTAGE 0
J 0
(-6350 1900);
PAINT SKYBLUE (-6350 1900);
DISPLAY INVISIBLE (-6350 1900);
FORCEPROP 2 LAST CDS_LIB mstr_symbols
J 0
(-6350 1900);
PAINT ORANGE (-6350 1900);
DISPLAY INVISIBLE (-6350 1900);
FORCEPROP 1 LAST SIZE 1B
J 0
(-6275 1850);
DISPLAY 0.893617 (-6275 1850);
PAINT GREEN (-6275 1850);
DISPLAY INVISIBLE (-6275 1850);
FORCEPROP 1 LAST BODY_TYPE PLUMBING
J 0
(-6395 1857);
DISPLAY 0.340426 (-6395 1857);
PAINT GREEN (-6395 1857);
DISPLAY INVISIBLE (-6395 1857);
FORCEPROP 1 LAST PATH I46
J 0
(-6275 1900);
DISPLAY 0.872340 (-6275 1900);
PAINT AQUA (-6275 1900);
DISPLAY INVISIBLE (-6275 1900);
FORCEPROP 1 LAST HDL_POWER GND
J 0
(-6350 2050);
DISPLAY 0.893617 (-6350 2050);
PAINT GREEN (-6350 2050);
DISPLAY INVISIBLE (-6350 2050);
FORCEADD GND..1
(-6350 1250);
FORCEPROP 3 LASTPIN (-6350 1300) SIG_NAME GND\g
J 0
(-6340 1310);
DISPLAY 0.659574 (-6340 1310);
PAINT MONO (-6340 1310);
DISPLAY INVISIBLE (-6340 1310);
FORCEPROP 1 LAST VOLTAGE 0
J 0
(-6350 1250);
PAINT SKYBLUE (-6350 1250);
DISPLAY INVISIBLE (-6350 1250);
FORCEPROP 2 LAST CDS_LIB mstr_symbols
J 0
(-6350 1250);
PAINT ORANGE (-6350 1250);
DISPLAY INVISIBLE (-6350 1250);
FORCEPROP 1 LAST SIZE 1B
J 0
(-6275 1200);
DISPLAY 0.893617 (-6275 1200);
PAINT GREEN (-6275 1200);
DISPLAY INVISIBLE (-6275 1200);
FORCEPROP 1 LAST BODY_TYPE PLUMBING
J 0
(-6395 1207);
DISPLAY 0.340426 (-6395 1207);
PAINT GREEN (-6395 1207);
DISPLAY INVISIBLE (-6395 1207);
FORCEPROP 1 LAST PATH I48
J 0
(-6275 1250);
DISPLAY 0.872340 (-6275 1250);
PAINT AQUA (-6275 1250);
DISPLAY INVISIBLE (-6275 1250);
FORCEPROP 1 LAST HDL_POWER GND
J 0
(-6350 1400);
DISPLAY 0.893617 (-6350 1400);
PAINT GREEN (-6350 1400);
DISPLAY INVISIBLE (-6350 1400);
FORCEADD GND..1
(-375 1775);
FORCEPROP 3 LASTPIN (-375 1825) SIG_NAME GND\g
J 0
(-365 1835);
DISPLAY 0.659574 (-365 1835);
PAINT MONO (-365 1835);
DISPLAY INVISIBLE (-365 1835);
FORCEPROP 1 LAST VOLTAGE 0
J 0
(-375 1775);
PAINT SKYBLUE (-375 1775);
DISPLAY INVISIBLE (-375 1775);
FORCEPROP 2 LAST CDS_LIB mstr_symbols
J 0
(-375 1775);
PAINT ORANGE (-375 1775);
DISPLAY INVISIBLE (-375 1775);
FORCEPROP 1 LAST SIZE 1B
J 0
(-300 1725);
DISPLAY 0.893617 (-300 1725);
PAINT GREEN (-300 1725);
DISPLAY INVISIBLE (-300 1725);
FORCEPROP 1 LAST BODY_TYPE PLUMBING
J 0
(-420 1732);
DISPLAY 0.340426 (-420 1732);
PAINT GREEN (-420 1732);
DISPLAY INVISIBLE (-420 1732);
FORCEPROP 1 LAST PATH I5
J 0
(-300 1775);
DISPLAY 0.872340 (-300 1775);
PAINT AQUA (-300 1775);
DISPLAY INVISIBLE (-300 1775);
FORCEPROP 1 LAST HDL_POWER GND
J 0
(-375 1925);
DISPLAY 0.893617 (-375 1925);
PAINT GREEN (-375 1925);
DISPLAY INVISIBLE (-375 1925);
FORCEADD CAP..1
(-7050 2225);
FORCEPROP 1 LAST LOCATION C5P33
J 0
(-7000 2325);
DISPLAY 0.617021 (-7000 2325);
PAINT AQUA (-7000 2325);
FORCEPROP 1 LAST PART_NUMBER C95333-006
R 1
J 0
(-7100 2050);
DISPLAY 0.617021 (-7100 2050);
PAINT BLUE (-7100 2050);
FORCEPROP 1 LAST VALUE 47UF
J 0
(-7000 2275);
DISPLAY 0.617021 (-7000 2275);
PAINT SKYBLUE (-7000 2275);
FORCEPROP 1 LAST TOLERANCE 20%
J 0
(-7000 2175);
DISPLAY 0.617021 (-7000 2175);
PAINT SKYBLUE (-7000 2175);
FORCEPROP 1 LAST PACK_TYPE 0805
J 0
(-7000 2075);
DISPLAY 0.617021 (-7000 2075);
PAINT SKYBLUE (-7000 2075);
FORCEPROP 1 LASTPIN (-7050 2125) $PN 2
J 0
(-7040 2105);
DISPLAY 0.617021 (-7040 2105);
PAINT GREEN (-7040 2105);
FORCEPROP 1 LASTPIN (-7050 2325) $PN 1
J 0
(-7040 2305);
DISPLAY 0.617021 (-7040 2305);
PAINT GREEN (-7040 2305);
FORCEPROP 1 LAST VOLTAGE 4V
J 0
(-7000 2225);
PAINT SKYBLUE (-7000 2225);
DISPLAY INVISIBLE (-7000 2225);
FORCEPROP 1 LAST MATERIAL X6S
J 0
(-7000 2125);
PAINT SKYBLUE (-7000 2125);
DISPLAY INVISIBLE (-7000 2125);
FORCEPROP 2 LAST BOM_COST PROC_SOCKET
J 0
(-7000 2425);
DISPLAY 1.021277 (-7000 2425);
PAINT ORANGE (-7000 2425);
DISPLAY INVISIBLE (-7000 2425);
FORCEPROP 2 LAST CDS_LIB mstr_discrete
J 0
(-7050 2225);
PAINT ORANGE (-7050 2225);
DISPLAY INVISIBLE (-7050 2225);
FORCEPROP 2 LAST CDS_SEC 1
J 0
(-7000 2425);
PAINT MONO (-7000 2425);
DISPLAY INVISIBLE (-7000 2425);
FORCEPROP 2 LAST $SEC 1
J 0
(-7000 2425);
PAINT MONO (-7000 2425);
DISPLAY INVISIBLE (-7000 2425);
FORCEPROP 2 LAST CDS_LOCATION C5P33
J 0
(-7000 2325);
DISPLAY 0.617021 (-7000 2325);
PAINT AQUA (-7000 2325);
DISPLAY INVISIBLE (-7000 2325);
FORCEPROP 1 LAST PATH I50
J 0
(-7000 2375);
DISPLAY 0.978723 (-7000 2375);
PAINT WHITE (-7000 2375);
DISPLAY INVISIBLE (-7000 2375);
FORCEPROP 2 LAST ROOM PVCCIN_CPU0_DECAP_VR
J 0
(-7000 2375);
DISPLAY 1.021277 (-7000 2375);
PAINT ORANGE (-7000 2375);
DISPLAY INVISIBLE (-7000 2375);
FORCEADD CAP..1
(-7375 2225);
FORCEPROP 1 LAST LOCATION C5P35
J 0
(-7325 2325);
DISPLAY 0.617021 (-7325 2325);
PAINT AQUA (-7325 2325);
FORCEPROP 1 LAST PART_NUMBER C95333-006
R 1
J 0
(-7425 2050);
DISPLAY 0.617021 (-7425 2050);
PAINT BLUE (-7425 2050);
FORCEPROP 1 LAST VALUE 47UF
J 0
(-7325 2275);
DISPLAY 0.617021 (-7325 2275);
PAINT SKYBLUE (-7325 2275);
FORCEPROP 1 LAST TOLERANCE 20%
J 0
(-7325 2175);
DISPLAY 0.617021 (-7325 2175);
PAINT SKYBLUE (-7325 2175);
FORCEPROP 1 LAST PACK_TYPE 0805
J 0
(-7325 2075);
DISPLAY 0.617021 (-7325 2075);
PAINT SKYBLUE (-7325 2075);
FORCEPROP 1 LASTPIN (-7375 2125) $PN 2
J 0
(-7365 2105);
DISPLAY 0.617021 (-7365 2105);
PAINT GREEN (-7365 2105);
FORCEPROP 1 LASTPIN (-7375 2325) $PN 1
J 0
(-7365 2305);
DISPLAY 0.617021 (-7365 2305);
PAINT GREEN (-7365 2305);
FORCEPROP 1 LAST VOLTAGE 4V
J 0
(-7325 2225);
PAINT SKYBLUE (-7325 2225);
DISPLAY INVISIBLE (-7325 2225);
FORCEPROP 1 LAST MATERIAL X6S
J 0
(-7325 2125);
PAINT SKYBLUE (-7325 2125);
DISPLAY INVISIBLE (-7325 2125);
FORCEPROP 2 LAST BOM_COST PROC_SOCKET
J 0
(-7325 2425);
DISPLAY 1.021277 (-7325 2425);
PAINT ORANGE (-7325 2425);
DISPLAY INVISIBLE (-7325 2425);
FORCEPROP 2 LAST CDS_LIB mstr_discrete
J 0
(-7375 2225);
PAINT ORANGE (-7375 2225);
DISPLAY INVISIBLE (-7375 2225);
FORCEPROP 2 LAST CDS_SEC 1
J 0
(-7325 2425);
PAINT MONO (-7325 2425);
DISPLAY INVISIBLE (-7325 2425);
FORCEPROP 2 LAST $SEC 1
J 0
(-7325 2425);
PAINT MONO (-7325 2425);
DISPLAY INVISIBLE (-7325 2425);
FORCEPROP 2 LAST CDS_LOCATION C5P35
J 0
(-7325 2325);
DISPLAY 0.617021 (-7325 2325);
PAINT AQUA (-7325 2325);
DISPLAY INVISIBLE (-7325 2325);
FORCEPROP 1 LAST PATH I51
J 0
(-7325 2375);
DISPLAY 0.978723 (-7325 2375);
PAINT WHITE (-7325 2375);
DISPLAY INVISIBLE (-7325 2375);
FORCEPROP 2 LAST ROOM PVCCIN_CPU0_DECAP_VR
J 0
(-7325 2375);
DISPLAY 1.021277 (-7325 2375);
PAINT ORANGE (-7325 2375);
DISPLAY INVISIBLE (-7325 2375);
FORCEADD CAP..1
(-7050 1575);
FORCEPROP 1 LAST LOCATION C5P32
J 0
(-7000 1675);
DISPLAY 0.617021 (-7000 1675);
PAINT AQUA (-7000 1675);
FORCEPROP 1 LAST PART_NUMBER C95333-006
R 1
J 0
(-7100 1400);
DISPLAY 0.617021 (-7100 1400);
PAINT BLUE (-7100 1400);
FORCEPROP 1 LAST VALUE 47UF
J 0
(-7000 1625);
DISPLAY 0.617021 (-7000 1625);
PAINT SKYBLUE (-7000 1625);
FORCEPROP 1 LAST TOLERANCE 20%
J 0
(-7000 1525);
DISPLAY 0.617021 (-7000 1525);
PAINT SKYBLUE (-7000 1525);
FORCEPROP 1 LAST PACK_TYPE 0805
J 0
(-7000 1425);
DISPLAY 0.617021 (-7000 1425);
PAINT SKYBLUE (-7000 1425);
FORCEPROP 1 LASTPIN (-7050 1475) $PN 2
J 0
(-7040 1455);
DISPLAY 0.617021 (-7040 1455);
PAINT GREEN (-7040 1455);
FORCEPROP 1 LASTPIN (-7050 1675) $PN 1
J 0
(-7040 1655);
DISPLAY 0.617021 (-7040 1655);
PAINT GREEN (-7040 1655);
FORCEPROP 1 LAST VOLTAGE 4V
J 0
(-7000 1575);
PAINT SKYBLUE (-7000 1575);
DISPLAY INVISIBLE (-7000 1575);
FORCEPROP 1 LAST MATERIAL X6S
J 0
(-7000 1475);
PAINT SKYBLUE (-7000 1475);
DISPLAY INVISIBLE (-7000 1475);
FORCEPROP 2 LAST BOM_COST PROC_SOCKET
J 0
(-7000 1775);
DISPLAY 1.021277 (-7000 1775);
PAINT ORANGE (-7000 1775);
DISPLAY INVISIBLE (-7000 1775);
FORCEPROP 2 LAST CDS_LIB mstr_discrete
J 0
(-7050 1575);
PAINT ORANGE (-7050 1575);
DISPLAY INVISIBLE (-7050 1575);
FORCEPROP 2 LAST CDS_SEC 1
J 0
(-7000 1775);
DISPLAY 1.021277 (-7000 1775);
PAINT ORANGE (-7000 1775);
DISPLAY INVISIBLE (-7000 1775);
FORCEPROP 2 LAST $SEC 1
J 0
(-7000 1775);
DISPLAY 0.680851 (-7000 1775);
PAINT MONO (-7000 1775);
DISPLAY INVISIBLE (-7000 1775);
FORCEPROP 2 LAST CDS_LOCATION C5P32
J 0
(-7000 1675);
DISPLAY 0.617021 (-7000 1675);
PAINT AQUA (-7000 1675);
DISPLAY INVISIBLE (-7000 1675);
FORCEPROP 1 LAST PATH I53
J 0
(-7000 1725);
DISPLAY 0.978723 (-7000 1725);
PAINT WHITE (-7000 1725);
DISPLAY INVISIBLE (-7000 1725);
FORCEPROP 2 LAST ROOM PVCCIN_CPU0_DECAP_VR
J 0
(-7000 1725);
DISPLAY 1.021277 (-7000 1725);
PAINT ORANGE (-7000 1725);
DISPLAY INVISIBLE (-7000 1725);
FORCEADD CAP..1
(-7375 1575);
FORCEPROP 1 LAST LOCATION C5P34
J 0
(-7325 1675);
DISPLAY 0.617021 (-7325 1675);
PAINT AQUA (-7325 1675);
FORCEPROP 1 LAST PART_NUMBER C95333-006
R 1
J 0
(-7425 1400);
DISPLAY 0.617021 (-7425 1400);
PAINT BLUE (-7425 1400);
FORCEPROP 1 LAST VALUE 47UF
J 0
(-7325 1625);
DISPLAY 0.617021 (-7325 1625);
PAINT SKYBLUE (-7325 1625);
FORCEPROP 1 LAST TOLERANCE 20%
J 0
(-7325 1525);
DISPLAY 0.617021 (-7325 1525);
PAINT SKYBLUE (-7325 1525);
FORCEPROP 1 LAST PACK_TYPE 0805
J 0
(-7325 1425);
DISPLAY 0.617021 (-7325 1425);
PAINT SKYBLUE (-7325 1425);
FORCEPROP 1 LASTPIN (-7375 1475) $PN 2
J 0
(-7365 1455);
DISPLAY 0.617021 (-7365 1455);
PAINT GREEN (-7365 1455);
FORCEPROP 1 LASTPIN (-7375 1675) $PN 1
J 0
(-7365 1655);
DISPLAY 0.617021 (-7365 1655);
PAINT GREEN (-7365 1655);
FORCEPROP 1 LAST VOLTAGE 4V
J 0
(-7325 1575);
PAINT SKYBLUE (-7325 1575);
DISPLAY INVISIBLE (-7325 1575);
FORCEPROP 1 LAST MATERIAL X6S
J 0
(-7325 1475);
PAINT SKYBLUE (-7325 1475);
DISPLAY INVISIBLE (-7325 1475);
FORCEPROP 2 LAST BOM_COST PROC_SOCKET
J 0
(-7325 1775);
DISPLAY 1.021277 (-7325 1775);
PAINT ORANGE (-7325 1775);
DISPLAY INVISIBLE (-7325 1775);
FORCEPROP 2 LAST CDS_LIB mstr_discrete
J 0
(-7375 1575);
PAINT ORANGE (-7375 1575);
DISPLAY INVISIBLE (-7375 1575);
FORCEPROP 2 LAST CDS_SEC 1
J 0
(-7325 1775);
DISPLAY 1.021277 (-7325 1775);
PAINT ORANGE (-7325 1775);
DISPLAY INVISIBLE (-7325 1775);
FORCEPROP 2 LAST $SEC 1
J 0
(-7325 1775);
DISPLAY 0.680851 (-7325 1775);
PAINT MONO (-7325 1775);
DISPLAY INVISIBLE (-7325 1775);
FORCEPROP 2 LAST CDS_LOCATION C5P34
J 0
(-7325 1675);
DISPLAY 0.617021 (-7325 1675);
PAINT AQUA (-7325 1675);
DISPLAY INVISIBLE (-7325 1675);
FORCEPROP 1 LAST PATH I54
J 0
(-7325 1725);
DISPLAY 0.978723 (-7325 1725);
PAINT WHITE (-7325 1725);
DISPLAY INVISIBLE (-7325 1725);
FORCEPROP 2 LAST ROOM PVCCIN_CPU0_DECAP_VR
J 0
(-7325 1725);
DISPLAY 1.021277 (-7325 1725);
PAINT ORANGE (-7325 1725);
DISPLAY INVISIBLE (-7325 1725);
FORCEADD CAP..1
(-5600 900);
FORCEPROP 1 LAST LOCATION C5P22
J 0
(-5550 1000);
DISPLAY 0.617021 (-5550 1000);
PAINT AQUA (-5550 1000);
FORCEPROP 1 LAST PART_NUMBER C95333-006
R 1
J 0
(-5650 725);
DISPLAY 0.617021 (-5650 725);
PAINT BLUE (-5650 725);
FORCEPROP 1 LAST VALUE 47UF
J 0
(-5550 950);
DISPLAY 0.617021 (-5550 950);
PAINT SKYBLUE (-5550 950);
FORCEPROP 1 LAST TOLERANCE 20%
J 0
(-5550 850);
DISPLAY 0.617021 (-5550 850);
PAINT SKYBLUE (-5550 850);
FORCEPROP 1 LAST PACK_TYPE 0805
J 0
(-5550 750);
DISPLAY 0.617021 (-5550 750);
PAINT SKYBLUE (-5550 750);
FORCEPROP 1 LASTPIN (-5600 800) $PN 2
J 0
(-5590 780);
DISPLAY 0.617021 (-5590 780);
PAINT GREEN (-5590 780);
FORCEPROP 1 LASTPIN (-5600 1000) $PN 1
J 0
(-5590 980);
DISPLAY 0.617021 (-5590 980);
PAINT GREEN (-5590 980);
FORCEPROP 1 LAST VOLTAGE 4V
J 0
(-5550 900);
PAINT SKYBLUE (-5550 900);
DISPLAY INVISIBLE (-5550 900);
FORCEPROP 1 LAST MATERIAL X6S
J 0
(-5550 800);
PAINT SKYBLUE (-5550 800);
DISPLAY INVISIBLE (-5550 800);
FORCEPROP 2 LAST BOM_COST PROC_SOCKET
J 0
(-5550 1100);
DISPLAY 1.021277 (-5550 1100);
PAINT ORANGE (-5550 1100);
DISPLAY INVISIBLE (-5550 1100);
FORCEPROP 2 LAST CDS_LIB mstr_discrete
J 0
(-5600 900);
PAINT ORANGE (-5600 900);
DISPLAY INVISIBLE (-5600 900);
FORCEPROP 2 LAST CDS_SEC 1
J 0
(-5550 1100);
DISPLAY 1.021277 (-5550 1100);
PAINT ORANGE (-5550 1100);
DISPLAY INVISIBLE (-5550 1100);
FORCEPROP 2 LAST $SEC 1
J 0
(-5550 1100);
DISPLAY 0.680851 (-5550 1100);
PAINT MONO (-5550 1100);
DISPLAY INVISIBLE (-5550 1100);
FORCEPROP 2 LAST CDS_LOCATION C5P22
J 0
(-5550 1000);
DISPLAY 0.617021 (-5550 1000);
PAINT AQUA (-5550 1000);
DISPLAY INVISIBLE (-5550 1000);
FORCEPROP 1 LAST PATH I55
J 0
(-5550 1050);
DISPLAY 0.978723 (-5550 1050);
PAINT WHITE (-5550 1050);
DISPLAY INVISIBLE (-5550 1050);
FORCEPROP 2 LAST ROOM PVCCIN_CPU0_DECAP_VR
J 0
(-5550 1050);
DISPLAY 1.021277 (-5550 1050);
PAINT ORANGE (-5550 1050);
DISPLAY INVISIBLE (-5550 1050);
FORCEADD CAP..1
(-5950 900);
FORCEPROP 1 LAST LOCATION C5P26
J 0
(-5900 1000);
DISPLAY 0.617021 (-5900 1000);
PAINT AQUA (-5900 1000);
FORCEPROP 1 LAST PART_NUMBER C95333-006
R 1
J 0
(-6000 725);
DISPLAY 0.617021 (-6000 725);
PAINT BLUE (-6000 725);
FORCEPROP 1 LAST VALUE 47UF
J 0
(-5900 950);
DISPLAY 0.617021 (-5900 950);
PAINT SKYBLUE (-5900 950);
FORCEPROP 1 LAST TOLERANCE 20%
J 0
(-5900 850);
DISPLAY 0.617021 (-5900 850);
PAINT SKYBLUE (-5900 850);
FORCEPROP 1 LAST PACK_TYPE 0805
J 0
(-5900 750);
DISPLAY 0.617021 (-5900 750);
PAINT SKYBLUE (-5900 750);
FORCEPROP 1 LASTPIN (-5950 800) $PN 2
J 0
(-5940 780);
DISPLAY 0.617021 (-5940 780);
PAINT GREEN (-5940 780);
FORCEPROP 1 LASTPIN (-5950 1000) $PN 1
J 0
(-5940 980);
DISPLAY 0.617021 (-5940 980);
PAINT GREEN (-5940 980);
FORCEPROP 1 LAST VOLTAGE 4V
J 0
(-5900 900);
PAINT SKYBLUE (-5900 900);
DISPLAY INVISIBLE (-5900 900);
FORCEPROP 1 LAST MATERIAL X6S
J 0
(-5900 800);
PAINT SKYBLUE (-5900 800);
DISPLAY INVISIBLE (-5900 800);
FORCEPROP 2 LAST BOM_COST PROC_SOCKET
J 0
(-5900 1100);
DISPLAY 1.021277 (-5900 1100);
PAINT ORANGE (-5900 1100);
DISPLAY INVISIBLE (-5900 1100);
FORCEPROP 2 LAST CDS_LIB mstr_discrete
J 0
(-5950 900);
PAINT ORANGE (-5950 900);
DISPLAY INVISIBLE (-5950 900);
FORCEPROP 2 LAST CDS_SEC 1
J 0
(-5900 1100);
DISPLAY 1.021277 (-5900 1100);
PAINT ORANGE (-5900 1100);
DISPLAY INVISIBLE (-5900 1100);
FORCEPROP 2 LAST $SEC 1
J 0
(-5900 1100);
DISPLAY 0.680851 (-5900 1100);
PAINT MONO (-5900 1100);
DISPLAY INVISIBLE (-5900 1100);
FORCEPROP 2 LAST CDS_LOCATION C5P26
J 0
(-5900 1000);
DISPLAY 0.617021 (-5900 1000);
PAINT AQUA (-5900 1000);
DISPLAY INVISIBLE (-5900 1000);
FORCEPROP 1 LAST PATH I56
J 0
(-5900 1050);
DISPLAY 0.978723 (-5900 1050);
PAINT WHITE (-5900 1050);
DISPLAY INVISIBLE (-5900 1050);
FORCEPROP 2 LAST ROOM PVCCIN_CPU0_DECAP_VR
J 0
(-5900 1050);
DISPLAY 1.021277 (-5900 1050);
PAINT ORANGE (-5900 1050);
DISPLAY INVISIBLE (-5900 1050);
FORCEADD CAP..1
(-6350 925);
FORCEPROP 1 LAST LOCATION C5P40
J 0
(-6300 1025);
DISPLAY 0.617021 (-6300 1025);
PAINT AQUA (-6300 1025);
FORCEPROP 1 LAST PART_NUMBER C95333-006
R 1
J 0
(-6400 750);
DISPLAY 0.617021 (-6400 750);
PAINT BLUE (-6400 750);
FORCEPROP 1 LAST VALUE 47UF
J 0
(-6300 975);
DISPLAY 0.617021 (-6300 975);
PAINT SKYBLUE (-6300 975);
FORCEPROP 1 LAST TOLERANCE 20%
J 0
(-6300 875);
DISPLAY 0.617021 (-6300 875);
PAINT SKYBLUE (-6300 875);
FORCEPROP 1 LAST PACK_TYPE 0805
J 0
(-6330 750);
DISPLAY 0.617021 (-6330 750);
PAINT SKYBLUE (-6330 750);
FORCEPROP 1 LASTPIN (-6350 825) $PN 2
J 0
(-6340 805);
DISPLAY 0.617021 (-6340 805);
PAINT GREEN (-6340 805);
FORCEPROP 1 LASTPIN (-6350 1025) $PN 1
J 0
(-6340 1005);
DISPLAY 0.617021 (-6340 1005);
PAINT GREEN (-6340 1005);
FORCEPROP 1 LAST VOLTAGE 4V
J 0
(-6300 925);
PAINT SKYBLUE (-6300 925);
DISPLAY INVISIBLE (-6300 925);
FORCEPROP 1 LAST MATERIAL X6S
J 0
(-6300 825);
PAINT SKYBLUE (-6300 825);
DISPLAY INVISIBLE (-6300 825);
FORCEPROP 2 LAST BOM_COST PROC_SOCKET
J 0
(-6300 1125);
DISPLAY 1.021277 (-6300 1125);
PAINT ORANGE (-6300 1125);
DISPLAY INVISIBLE (-6300 1125);
FORCEPROP 2 LAST CDS_LIB mstr_discrete
J 0
(-6350 925);
PAINT ORANGE (-6350 925);
DISPLAY INVISIBLE (-6350 925);
FORCEPROP 2 LAST CDS_SEC 1
J 0
(-6300 1125);
DISPLAY 1.021277 (-6300 1125);
PAINT ORANGE (-6300 1125);
DISPLAY INVISIBLE (-6300 1125);
FORCEPROP 2 LAST $SEC 1
J 0
(-6300 1125);
DISPLAY 0.680851 (-6300 1125);
PAINT MONO (-6300 1125);
DISPLAY INVISIBLE (-6300 1125);
FORCEPROP 2 LAST CDS_LOCATION C5P40
J 0
(-6300 1025);
DISPLAY 0.617021 (-6300 1025);
PAINT AQUA (-6300 1025);
DISPLAY INVISIBLE (-6300 1025);
FORCEPROP 1 LAST PATH I57
J 0
(-6300 1075);
DISPLAY 0.978723 (-6300 1075);
PAINT WHITE (-6300 1075);
DISPLAY INVISIBLE (-6300 1075);
FORCEPROP 2 LAST ROOM PVCCIN_CPU0_DECAP_VR
J 0
(-6300 1075);
DISPLAY 1.021277 (-6300 1075);
PAINT ORANGE (-6300 1075);
DISPLAY INVISIBLE (-6300 1075);
FORCEADD GND..1
(-6350 600);
FORCEPROP 3 LASTPIN (-6350 650) SIG_NAME GND\g
J 0
(-6340 660);
DISPLAY 0.659574 (-6340 660);
PAINT MONO (-6340 660);
DISPLAY INVISIBLE (-6340 660);
FORCEPROP 1 LAST VOLTAGE 0
J 0
(-6350 600);
PAINT SKYBLUE (-6350 600);
DISPLAY INVISIBLE (-6350 600);
FORCEPROP 1 LAST SIZE 1B
J 0
(-6275 550);
DISPLAY 0.893617 (-6275 550);
PAINT GREEN (-6275 550);
DISPLAY INVISIBLE (-6275 550);
FORCEPROP 2 LAST CDS_LIB mstr_symbols
J 0
(-6350 600);
PAINT ORANGE (-6350 600);
DISPLAY INVISIBLE (-6350 600);
FORCEPROP 1 LAST BODY_TYPE PLUMBING
J 0
(-6395 557);
DISPLAY 0.340426 (-6395 557);
PAINT GREEN (-6395 557);
DISPLAY INVISIBLE (-6395 557);
FORCEPROP 1 LAST PATH I58
J 0
(-6275 600);
DISPLAY 0.872340 (-6275 600);
PAINT AQUA (-6275 600);
DISPLAY INVISIBLE (-6275 600);
FORCEPROP 1 LAST HDL_POWER GND
J 0
(-6350 750);
DISPLAY 0.893617 (-6350 750);
PAINT GREEN (-6350 750);
DISPLAY INVISIBLE (-6350 750);
FORCEADD CAP..1
(-6700 925);
FORCEPROP 1 LAST LOCATION C5P42
J 0
(-6650 1025);
DISPLAY 0.617021 (-6650 1025);
PAINT AQUA (-6650 1025);
FORCEPROP 1 LAST PART_NUMBER C95333-006
R 1
J 0
(-6750 750);
DISPLAY 0.617021 (-6750 750);
PAINT BLUE (-6750 750);
FORCEPROP 1 LAST VALUE 47UF
J 0
(-6650 975);
DISPLAY 0.617021 (-6650 975);
PAINT SKYBLUE (-6650 975);
FORCEPROP 1 LAST TOLERANCE 20%
J 0
(-6650 875);
DISPLAY 0.617021 (-6650 875);
PAINT SKYBLUE (-6650 875);
FORCEPROP 1 LAST PACK_TYPE 0805
J 0
(-6690 745);
DISPLAY 0.617021 (-6690 745);
PAINT SKYBLUE (-6690 745);
FORCEPROP 1 LASTPIN (-6700 825) $PN 2
J 0
(-6690 805);
DISPLAY 0.617021 (-6690 805);
PAINT GREEN (-6690 805);
FORCEPROP 1 LASTPIN (-6700 1025) $PN 1
J 0
(-6690 1005);
DISPLAY 0.617021 (-6690 1005);
PAINT GREEN (-6690 1005);
FORCEPROP 1 LAST VOLTAGE 4V
J 0
(-6650 925);
PAINT SKYBLUE (-6650 925);
DISPLAY INVISIBLE (-6650 925);
FORCEPROP 1 LAST MATERIAL X6S
J 0
(-6650 825);
PAINT SKYBLUE (-6650 825);
DISPLAY INVISIBLE (-6650 825);
FORCEPROP 2 LAST BOM_COST PROC_SOCKET
J 0
(-6650 1125);
DISPLAY 1.021277 (-6650 1125);
PAINT ORANGE (-6650 1125);
DISPLAY INVISIBLE (-6650 1125);
FORCEPROP 2 LAST CDS_LIB mstr_discrete
J 0
(-6700 925);
PAINT ORANGE (-6700 925);
DISPLAY INVISIBLE (-6700 925);
FORCEPROP 2 LAST CDS_SEC 1
J 0
(-6650 1125);
DISPLAY 1.021277 (-6650 1125);
PAINT ORANGE (-6650 1125);
DISPLAY INVISIBLE (-6650 1125);
FORCEPROP 2 LAST $SEC 1
J 0
(-6650 1125);
DISPLAY 0.680851 (-6650 1125);
PAINT MONO (-6650 1125);
DISPLAY INVISIBLE (-6650 1125);
FORCEPROP 2 LAST CDS_LOCATION C5P42
J 0
(-6650 1025);
DISPLAY 0.617021 (-6650 1025);
PAINT AQUA (-6650 1025);
DISPLAY INVISIBLE (-6650 1025);
FORCEPROP 1 LAST PATH I59
J 0
(-6650 1075);
DISPLAY 0.978723 (-6650 1075);
PAINT WHITE (-6650 1075);
DISPLAY INVISIBLE (-6650 1075);
FORCEPROP 2 LAST ROOM PVCCIN_CPU0_DECAP_VR
J 0
(-6650 1075);
DISPLAY 1.021277 (-6650 1075);
PAINT ORANGE (-6650 1075);
DISPLAY INVISIBLE (-6650 1075);
FORCEADD CAP..1
(-3000 2175);
FORCEPROP 1 LAST LOCATION C5P10
J 0
(-2950 2275);
DISPLAY 0.617021 (-2950 2275);
PAINT AQUA (-2950 2275);
FORCEPROP 1 LAST PART_NUMBER C95333-006
R 1
J 0
(-3050 2000);
DISPLAY 0.617021 (-3050 2000);
PAINT BLUE (-3050 2000);
FORCEPROP 1 LAST VALUE 47UF
J 0
(-2950 2225);
DISPLAY 0.617021 (-2950 2225);
PAINT SKYBLUE (-2950 2225);
FORCEPROP 1 LAST TOLERANCE 20%
J 0
(-2950 2125);
DISPLAY 0.617021 (-2950 2125);
PAINT SKYBLUE (-2950 2125);
FORCEPROP 1 LAST PACK_TYPE 0805
J 0
(-2950 2025);
DISPLAY 0.617021 (-2950 2025);
PAINT SKYBLUE (-2950 2025);
FORCEPROP 1 LASTPIN (-3000 2075) $PN 2
J 0
(-2990 2055);
DISPLAY 0.617021 (-2990 2055);
PAINT GREEN (-2990 2055);
FORCEPROP 1 LASTPIN (-3000 2275) $PN 1
J 0
(-2990 2255);
DISPLAY 0.617021 (-2990 2255);
PAINT GREEN (-2990 2255);
FORCEPROP 1 LAST VOLTAGE 4V
J 0
(-2950 2175);
PAINT SKYBLUE (-2950 2175);
DISPLAY INVISIBLE (-2950 2175);
FORCEPROP 1 LAST MATERIAL X6S
J 0
(-2950 2075);
PAINT SKYBLUE (-2950 2075);
DISPLAY INVISIBLE (-2950 2075);
FORCEPROP 2 LAST CDS_LIB mstr_discrete
J 0
(-3000 2175);
PAINT ORANGE (-3000 2175);
DISPLAY INVISIBLE (-3000 2175);
FORCEPROP 2 LAST BOM_COST PROC_SOCKET
J 0
(-2950 2375);
DISPLAY 1.021277 (-2950 2375);
PAINT ORANGE (-2950 2375);
DISPLAY INVISIBLE (-2950 2375);
FORCEPROP 2 LAST CDS_SEC 1
J 0
(-2950 2375);
DISPLAY 1.021277 (-2950 2375);
PAINT ORANGE (-2950 2375);
DISPLAY INVISIBLE (-2950 2375);
FORCEPROP 2 LAST $SEC 1
J 0
(-2950 2375);
DISPLAY 0.680851 (-2950 2375);
PAINT MONO (-2950 2375);
DISPLAY INVISIBLE (-2950 2375);
FORCEPROP 2 LAST CDS_LOCATION C5P10
J 0
(-2950 2275);
DISPLAY 0.617021 (-2950 2275);
PAINT AQUA (-2950 2275);
DISPLAY INVISIBLE (-2950 2275);
FORCEPROP 1 LAST PATH I6
J 0
(-2950 2325);
DISPLAY 0.978723 (-2950 2325);
PAINT WHITE (-2950 2325);
DISPLAY INVISIBLE (-2950 2325);
FORCEPROP 2 LAST ROOM PVCCIN_CPU0_DECAP_VR
J 0
(-2950 2325);
DISPLAY 1.021277 (-2950 2325);
PAINT ORANGE (-2950 2325);
DISPLAY INVISIBLE (-2950 2325);
FORCEADD CAP..1
(-7050 925);
FORCEPROP 1 LAST LOCATION C5P43
J 0
(-7000 1025);
DISPLAY 0.617021 (-7000 1025);
PAINT AQUA (-7000 1025);
FORCEPROP 1 LAST PART_NUMBER C95333-006
J 0
(-7000 775);
DISPLAY 0.617021 (-7000 775);
PAINT BLUE (-7000 775);
FORCEPROP 1 LAST VALUE 47UF
J 0
(-7000 975);
DISPLAY 0.617021 (-7000 975);
PAINT SKYBLUE (-7000 975);
FORCEPROP 1 LAST TOLERANCE 20%
J 0
(-7000 875);
DISPLAY 0.617021 (-7000 875);
PAINT SKYBLUE (-7000 875);
FORCEPROP 1 LAST PACK_TYPE 0805
J 0
(-7030 740);
DISPLAY 0.617021 (-7030 740);
PAINT SKYBLUE (-7030 740);
FORCEPROP 1 LASTPIN (-7050 825) $PN 2
J 0
(-7040 805);
DISPLAY 0.617021 (-7040 805);
PAINT GREEN (-7040 805);
FORCEPROP 1 LASTPIN (-7050 1025) $PN 1
J 0
(-7040 1005);
DISPLAY 0.617021 (-7040 1005);
PAINT GREEN (-7040 1005);
FORCEPROP 1 LAST VOLTAGE 4V
J 0
(-7000 925);
PAINT SKYBLUE (-7000 925);
DISPLAY INVISIBLE (-7000 925);
FORCEPROP 1 LAST MATERIAL X6S
J 0
(-7000 825);
PAINT SKYBLUE (-7000 825);
DISPLAY INVISIBLE (-7000 825);
FORCEPROP 2 LAST BOM_COST PROC_SOCKET
J 0
(-7000 1125);
DISPLAY 1.021277 (-7000 1125);
PAINT ORANGE (-7000 1125);
DISPLAY INVISIBLE (-7000 1125);
FORCEPROP 2 LAST CDS_LIB mstr_discrete
J 0
(-7050 925);
PAINT ORANGE (-7050 925);
DISPLAY INVISIBLE (-7050 925);
FORCEPROP 2 LAST CDS_SEC 1
J 0
(-7000 1125);
DISPLAY 1.021277 (-7000 1125);
PAINT ORANGE (-7000 1125);
DISPLAY INVISIBLE (-7000 1125);
FORCEPROP 2 LAST $SEC 1
J 0
(-7000 1125);
DISPLAY 0.680851 (-7000 1125);
PAINT MONO (-7000 1125);
DISPLAY INVISIBLE (-7000 1125);
FORCEPROP 2 LAST CDS_LOCATION C5P43
J 0
(-7000 1025);
DISPLAY 0.617021 (-7000 1025);
PAINT AQUA (-7000 1025);
DISPLAY INVISIBLE (-7000 1025);
FORCEPROP 1 LAST PATH I60
J 0
(-7000 1075);
DISPLAY 0.978723 (-7000 1075);
PAINT WHITE (-7000 1075);
DISPLAY INVISIBLE (-7000 1075);
FORCEPROP 2 LAST ROOM PVCCIN_CPU0_DECAP_VR
J 0
(-7000 1075);
DISPLAY 1.021277 (-7000 1075);
PAINT ORANGE (-7000 1075);
DISPLAY INVISIBLE (-7000 1075);
FORCEADD CAP..1
(-7375 925);
FORCEPROP 1 LAST LOCATION C5P44
J 0
(-7325 1025);
DISPLAY 0.617021 (-7325 1025);
PAINT AQUA (-7325 1025);
FORCEPROP 1 LAST PART_NUMBER C95333-006
J 0
(-7325 775);
DISPLAY 0.617021 (-7325 775);
PAINT BLUE (-7325 775);
FORCEPROP 1 LAST VALUE 47UF
J 0
(-7325 975);
DISPLAY 0.617021 (-7325 975);
PAINT SKYBLUE (-7325 975);
FORCEPROP 1 LAST TOLERANCE 20%
J 0
(-7325 875);
DISPLAY 0.617021 (-7325 875);
PAINT SKYBLUE (-7325 875);
FORCEPROP 1 LAST PACK_TYPE 0805
J 0
(-7365 735);
DISPLAY 0.617021 (-7365 735);
PAINT SKYBLUE (-7365 735);
FORCEPROP 1 LASTPIN (-7375 825) $PN 2
J 0
(-7365 805);
DISPLAY 0.617021 (-7365 805);
PAINT GREEN (-7365 805);
FORCEPROP 1 LASTPIN (-7375 1025) $PN 1
J 0
(-7365 1005);
DISPLAY 0.617021 (-7365 1005);
PAINT GREEN (-7365 1005);
FORCEPROP 1 LAST VOLTAGE 4V
J 0
(-7325 925);
PAINT SKYBLUE (-7325 925);
DISPLAY INVISIBLE (-7325 925);
FORCEPROP 1 LAST MATERIAL X6S
J 0
(-7325 825);
PAINT SKYBLUE (-7325 825);
DISPLAY INVISIBLE (-7325 825);
FORCEPROP 2 LAST BOM_COST PROC_SOCKET
J 0
(-7325 1125);
DISPLAY 1.021277 (-7325 1125);
PAINT ORANGE (-7325 1125);
DISPLAY INVISIBLE (-7325 1125);
FORCEPROP 2 LAST CDS_LIB mstr_discrete
J 0
(-7375 925);
PAINT ORANGE (-7375 925);
DISPLAY INVISIBLE (-7375 925);
FORCEPROP 2 LAST CDS_SEC 1
J 0
(-7325 1125);
DISPLAY 1.021277 (-7325 1125);
PAINT ORANGE (-7325 1125);
DISPLAY INVISIBLE (-7325 1125);
FORCEPROP 2 LAST $SEC 1
J 0
(-7325 1125);
DISPLAY 0.680851 (-7325 1125);
PAINT MONO (-7325 1125);
DISPLAY INVISIBLE (-7325 1125);
FORCEPROP 2 LAST CDS_LOCATION C5P44
J 0
(-7325 1025);
DISPLAY 0.617021 (-7325 1025);
PAINT AQUA (-7325 1025);
DISPLAY INVISIBLE (-7325 1025);
FORCEPROP 1 LAST PATH I61
J 0
(-7325 1075);
DISPLAY 0.978723 (-7325 1075);
PAINT WHITE (-7325 1075);
DISPLAY INVISIBLE (-7325 1075);
FORCEPROP 2 LAST ROOM PVCCIN_CPU0_DECAP_VR
J 0
(-7325 1075);
DISPLAY 1.021277 (-7325 1075);
PAINT ORANGE (-7325 1075);
DISPLAY INVISIBLE (-7325 1075);
FORCEADD PVCCIN_CPU0..1
(-7725 2500);
FORCEPROP 3 LASTPIN (-7725 2450) SIG_NAME PVCCIN_CPU0\g
J 0
(-7715 2460);
DISPLAY 0.659574 (-7715 2460);
PAINT MONO (-7715 2460);
DISPLAY INVISIBLE (-7715 2460);
FORCEPROP 1 LAST VOLTAGE 2.0V
J 0
(-7770 2457);
DISPLAY 0.340426 (-7770 2457);
PAINT SKYBLUE (-7770 2457);
DISPLAY INVISIBLE (-7770 2457);
FORCEPROP 2 LAST CDS_LIB mstr_symbols
J 0
(-7725 2500);
PAINT ORANGE (-7725 2500);
DISPLAY INVISIBLE (-7725 2500);
FORCEPROP 1 LAST BODY_TYPE PLUMBING
J 0
(-7770 2457);
DISPLAY 0.340426 (-7770 2457);
PAINT GREEN (-7770 2457);
DISPLAY INVISIBLE (-7770 2457);
FORCEPROP 1 LAST PATH I62
J 0
(-7675 2525);
DISPLAY 0.872340 (-7675 2525);
PAINT AQUA (-7675 2525);
DISPLAY INVISIBLE (-7675 2525);
FORCEPROP 1 LAST HDL_POWER PVCCIN_CPU0
J 1
(-7725 2550);
DISPLAY 0.872340 (-7725 2550);
PAINT GREEN (-7725 2550);
DISPLAY INVISIBLE (-7725 2550);
FORCEADD CAP..1
(-7725 2225);
FORCEPROP 1 LAST LOCATION C5P37
J 0
(-7675 2325);
DISPLAY 0.617021 (-7675 2325);
PAINT AQUA (-7675 2325);
FORCEPROP 1 LAST PART_NUMBER C95333-006
R 1
J 0
(-7775 2050);
DISPLAY 0.617021 (-7775 2050);
PAINT BLUE (-7775 2050);
FORCEPROP 1 LAST VALUE 47UF
J 0
(-7675 2275);
DISPLAY 0.617021 (-7675 2275);
PAINT SKYBLUE (-7675 2275);
FORCEPROP 1 LAST TOLERANCE 20%
J 0
(-7675 2175);
DISPLAY 0.617021 (-7675 2175);
PAINT SKYBLUE (-7675 2175);
FORCEPROP 1 LAST PACK_TYPE 0805
J 0
(-7675 2075);
DISPLAY 0.617021 (-7675 2075);
PAINT SKYBLUE (-7675 2075);
FORCEPROP 1 LAST MATERIAL X6S
J 0
(-7675 2125);
DISPLAY 0.617021 (-7675 2125);
PAINT SKYBLUE (-7675 2125);
FORCEPROP 1 LASTPIN (-7725 2125) $PN 2
J 0
(-7715 2105);
DISPLAY 0.617021 (-7715 2105);
PAINT GREEN (-7715 2105);
FORCEPROP 1 LASTPIN (-7725 2325) $PN 1
J 0
(-7715 2305);
DISPLAY 0.617021 (-7715 2305);
PAINT GREEN (-7715 2305);
FORCEPROP 1 LAST VOLTAGE 4V
J 0
(-7675 2225);
PAINT SKYBLUE (-7675 2225);
DISPLAY INVISIBLE (-7675 2225);
FORCEPROP 2 LAST BOM_COST PROC_SOCKET
J 0
(-7675 2425);
DISPLAY 1.021277 (-7675 2425);
PAINT ORANGE (-7675 2425);
DISPLAY INVISIBLE (-7675 2425);
FORCEPROP 2 LAST CDS_LIB mstr_discrete
J 0
(-7725 2225);
PAINT ORANGE (-7725 2225);
DISPLAY INVISIBLE (-7725 2225);
FORCEPROP 2 LAST CDS_SEC 1
J 0
(-7675 2425);
PAINT MONO (-7675 2425);
DISPLAY INVISIBLE (-7675 2425);
FORCEPROP 2 LAST $SEC 1
J 0
(-7675 2425);
PAINT MONO (-7675 2425);
DISPLAY INVISIBLE (-7675 2425);
FORCEPROP 2 LAST CDS_LOCATION C5P37
J 0
(-7675 2325);
DISPLAY 0.617021 (-7675 2325);
PAINT AQUA (-7675 2325);
DISPLAY INVISIBLE (-7675 2325);
FORCEPROP 1 LAST PATH I63
J 0
(-7675 2375);
DISPLAY 0.978723 (-7675 2375);
PAINT WHITE (-7675 2375);
DISPLAY INVISIBLE (-7675 2375);
FORCEPROP 2 LAST ROOM PVCCIN_CPU0_DECAP_VR
J 0
(-7675 2375);
DISPLAY 1.021277 (-7675 2375);
PAINT ORANGE (-7675 2375);
DISPLAY INVISIBLE (-7675 2375);
FORCEADD PVCCIN_CPU0..1
(-7725 1850);
FORCEPROP 3 LASTPIN (-7725 1800) SIG_NAME PVCCIN_CPU0\g
J 0
(-7715 1810);
DISPLAY 0.659574 (-7715 1810);
PAINT MONO (-7715 1810);
DISPLAY INVISIBLE (-7715 1810);
FORCEPROP 1 LAST VOLTAGE 2.0V
J 0
(-7770 1807);
DISPLAY 0.340426 (-7770 1807);
PAINT SKYBLUE (-7770 1807);
DISPLAY INVISIBLE (-7770 1807);
FORCEPROP 2 LAST CDS_LIB mstr_symbols
J 0
(-7725 1850);
PAINT ORANGE (-7725 1850);
DISPLAY INVISIBLE (-7725 1850);
FORCEPROP 1 LAST BODY_TYPE PLUMBING
J 0
(-7770 1807);
DISPLAY 0.340426 (-7770 1807);
PAINT GREEN (-7770 1807);
DISPLAY INVISIBLE (-7770 1807);
FORCEPROP 1 LAST PATH I64
J 0
(-7675 1875);
DISPLAY 0.872340 (-7675 1875);
PAINT AQUA (-7675 1875);
DISPLAY INVISIBLE (-7675 1875);
FORCEPROP 1 LAST HDL_POWER PVCCIN_CPU0
J 1
(-7725 1900);
DISPLAY 0.872340 (-7725 1900);
PAINT GREEN (-7725 1900);
DISPLAY INVISIBLE (-7725 1900);
FORCEADD CAP..1
(-7725 1575);
FORCEPROP 1 LAST LOCATION C5P36
J 0
(-7675 1675);
DISPLAY 0.617021 (-7675 1675);
PAINT AQUA (-7675 1675);
FORCEPROP 1 LAST PART_NUMBER C95333-006
J 0
(-7675 1475);
DISPLAY 0.617021 (-7675 1475);
PAINT BLUE (-7675 1475);
FORCEPROP 1 LAST VALUE 47UF
J 0
(-7675 1625);
DISPLAY 0.617021 (-7675 1625);
PAINT SKYBLUE (-7675 1625);
FORCEPROP 1 LAST TOLERANCE 20%
J 0
(-7675 1525);
DISPLAY 0.617021 (-7675 1525);
PAINT SKYBLUE (-7675 1525);
FORCEPROP 1 LAST PACK_TYPE 0805
J 0
(-7675 1425);
DISPLAY 0.617021 (-7675 1425);
PAINT SKYBLUE (-7675 1425);
FORCEPROP 1 LASTPIN (-7725 1475) $PN 2
J 0
(-7715 1455);
DISPLAY 0.617021 (-7715 1455);
PAINT GREEN (-7715 1455);
FORCEPROP 1 LASTPIN (-7725 1675) $PN 1
J 0
(-7715 1655);
DISPLAY 0.617021 (-7715 1655);
PAINT GREEN (-7715 1655);
FORCEPROP 1 LAST VOLTAGE 4V
J 0
(-7675 1575);
PAINT SKYBLUE (-7675 1575);
DISPLAY INVISIBLE (-7675 1575);
FORCEPROP 1 LAST MATERIAL X6S
J 0
(-7675 1475);
PAINT SKYBLUE (-7675 1475);
DISPLAY INVISIBLE (-7675 1475);
FORCEPROP 2 LAST BOM_COST PROC_SOCKET
J 0
(-7675 1775);
DISPLAY 1.021277 (-7675 1775);
PAINT ORANGE (-7675 1775);
DISPLAY INVISIBLE (-7675 1775);
FORCEPROP 2 LAST CDS_LIB mstr_discrete
J 0
(-7725 1575);
PAINT ORANGE (-7725 1575);
DISPLAY INVISIBLE (-7725 1575);
FORCEPROP 2 LAST CDS_SEC 1
J 0
(-7675 1775);
DISPLAY 1.021277 (-7675 1775);
PAINT ORANGE (-7675 1775);
DISPLAY INVISIBLE (-7675 1775);
FORCEPROP 2 LAST $SEC 1
J 0
(-7675 1775);
DISPLAY 0.680851 (-7675 1775);
PAINT MONO (-7675 1775);
DISPLAY INVISIBLE (-7675 1775);
FORCEPROP 2 LAST CDS_LOCATION C5P36
J 0
(-7675 1675);
DISPLAY 0.617021 (-7675 1675);
PAINT AQUA (-7675 1675);
DISPLAY INVISIBLE (-7675 1675);
FORCEPROP 1 LAST PATH I65
J 0
(-7675 1725);
DISPLAY 0.978723 (-7675 1725);
PAINT WHITE (-7675 1725);
DISPLAY INVISIBLE (-7675 1725);
FORCEPROP 2 LAST ROOM PVCCIN_CPU0_DECAP_VR
J 0
(-7675 1725);
DISPLAY 1.021277 (-7675 1725);
PAINT ORANGE (-7675 1725);
DISPLAY INVISIBLE (-7675 1725);
FORCEADD PVCCIN_CPU0..1
(-7725 1200);
FORCEPROP 3 LASTPIN (-7725 1150) SIG_NAME PVCCIN_CPU0\g
J 0
(-7715 1160);
DISPLAY 0.659574 (-7715 1160);
PAINT MONO (-7715 1160);
DISPLAY INVISIBLE (-7715 1160);
FORCEPROP 1 LAST VOLTAGE 2.0V
J 0
(-7770 1157);
DISPLAY 0.340426 (-7770 1157);
PAINT SKYBLUE (-7770 1157);
DISPLAY INVISIBLE (-7770 1157);
FORCEPROP 2 LAST CDS_LIB mstr_symbols
J 0
(-7725 1200);
PAINT ORANGE (-7725 1200);
DISPLAY INVISIBLE (-7725 1200);
FORCEPROP 1 LAST BODY_TYPE PLUMBING
J 0
(-7770 1157);
DISPLAY 0.340426 (-7770 1157);
PAINT GREEN (-7770 1157);
DISPLAY INVISIBLE (-7770 1157);
FORCEPROP 1 LAST PATH I66
J 0
(-7675 1225);
DISPLAY 0.872340 (-7675 1225);
PAINT AQUA (-7675 1225);
DISPLAY INVISIBLE (-7675 1225);
FORCEPROP 1 LAST HDL_POWER PVCCIN_CPU0
J 1
(-7725 1250);
DISPLAY 0.872340 (-7725 1250);
PAINT GREEN (-7725 1250);
DISPLAY INVISIBLE (-7725 1250);
FORCEADD CAP_A..1
(-800 4450);
FORCEPROP 1 LAST LOCATION C6D8
J 0
(-750 4550);
DISPLAY 0.617021 (-750 4550);
PAINT AQUA (-750 4550);
FORCEPROP 1 LAST PART_NUMBER E15431-004
J 0
(-750 4300);
DISPLAY 0.617021 (-750 4300);
PAINT BLUE (-750 4300);
FORCEPROP 1 LAST VALUE 22.0UF
J 0
(-750 4500);
DISPLAY 0.617021 (-750 4500);
PAINT SKYBLUE (-750 4500);
FORCEPROP 1 LAST TOLERANCE 20%
J 0
(-750 4400);
DISPLAY 0.617021 (-750 4400);
PAINT SKYBLUE (-750 4400);
FORCEPROP 1 LAST PACK_TYPE 0603V
J 0
(-750 4250);
DISPLAY 0.617021 (-750 4250);
PAINT SKYBLUE (-750 4250);
FORCEPROP 1 LAST VOLTAGE 4V
J 0
(-750 4450);
DISPLAY 0.617021 (-750 4450);
PAINT SKYBLUE (-750 4450);
FORCEPROP 1 LAST MATERIAL X6S
J 0
(-750 4350);
DISPLAY 0.617021 (-750 4350);
PAINT SKYBLUE (-750 4350);
FORCEPROP 1 LASTPIN (-800 4550) $PN 1
J 0
(-790 4530);
DISPLAY 0.617021 (-790 4530);
PAINT GREEN (-790 4530);
FORCEPROP 1 LASTPIN (-800 4350) $PN 2
J 0
(-790 4330);
DISPLAY 0.617021 (-790 4330);
PAINT GREEN (-790 4330);
FORCEPROP 2 LAST CDS_LOCATION C6D8
J 0
(-750 4550);
DISPLAY 0.617021 (-750 4550);
PAINT AQUA (-750 4550);
DISPLAY INVISIBLE (-750 4550);
FORCEPROP 2 LAST BOM_COST PROC_SOCKET
J 0
(-750 4650);
DISPLAY 1.021277 (-750 4650);
PAINT ORANGE (-750 4650);
DISPLAY INVISIBLE (-750 4650);
FORCEPROP 2 LAST CDS_LIB dev_discrete
J 0
(-800 4450);
PAINT ORANGE (-800 4450);
DISPLAY INVISIBLE (-800 4450);
FORCEPROP 2 LAST CDS_SEC 1
J 0
(-750 4650);
PAINT MONO (-750 4650);
DISPLAY INVISIBLE (-750 4650);
FORCEPROP 2 LAST $SEC 1
J 0
(-750 4650);
PAINT MONO (-750 4650);
DISPLAY INVISIBLE (-750 4650);
FORCEPROP 1 LAST PATH I68
J 0
(-750 4600);
DISPLAY 0.978723 (-750 4600);
PAINT WHITE (-750 4600);
DISPLAY INVISIBLE (-750 4600);
FORCEPROP 2 LAST ROOM PVCCIN_CPU0_DECAP_VR
J 0
(-750 4600);
DISPLAY 1.021277 (-750 4600);
PAINT ORANGE (-750 4600);
DISPLAY INVISIBLE (-750 4600);
FORCEADD CAP_A..1
(-1100 4450);
FORCEPROP 1 LAST LOCATION C5D38
J 0
(-1050 4550);
DISPLAY 0.617021 (-1050 4550);
PAINT AQUA (-1050 4550);
FORCEPROP 1 LAST PART_NUMBER E15431-004
J 0
(-1050 4300);
DISPLAY 0.617021 (-1050 4300);
PAINT BLUE (-1050 4300);
FORCEPROP 1 LAST VALUE 22.0UF
J 0
(-1050 4500);
DISPLAY 0.617021 (-1050 4500);
PAINT SKYBLUE (-1050 4500);
FORCEPROP 1 LAST TOLERANCE 20%
J 0
(-1050 4400);
DISPLAY 0.617021 (-1050 4400);
PAINT SKYBLUE (-1050 4400);
FORCEPROP 1 LAST PACK_TYPE 0603V
J 0
(-1050 4250);
DISPLAY 0.617021 (-1050 4250);
PAINT SKYBLUE (-1050 4250);
FORCEPROP 1 LAST VOLTAGE 4V
J 0
(-1050 4450);
DISPLAY 0.617021 (-1050 4450);
PAINT SKYBLUE (-1050 4450);
FORCEPROP 1 LAST MATERIAL X6S
J 0
(-1050 4350);
DISPLAY 0.617021 (-1050 4350);
PAINT SKYBLUE (-1050 4350);
FORCEPROP 1 LASTPIN (-1100 4550) $PN 1
J 0
(-1090 4530);
DISPLAY 0.617021 (-1090 4530);
PAINT GREEN (-1090 4530);
FORCEPROP 1 LASTPIN (-1100 4350) $PN 2
J 0
(-1090 4330);
DISPLAY 0.617021 (-1090 4330);
PAINT GREEN (-1090 4330);
FORCEPROP 2 LAST CDS_LOCATION C5D38
J 0
(-1050 4550);
DISPLAY 0.617021 (-1050 4550);
PAINT AQUA (-1050 4550);
DISPLAY INVISIBLE (-1050 4550);
FORCEPROP 2 LAST BOM_COST PROC_SOCKET
J 0
(-1050 4650);
DISPLAY 1.021277 (-1050 4650);
PAINT ORANGE (-1050 4650);
DISPLAY INVISIBLE (-1050 4650);
FORCEPROP 2 LAST CDS_LIB dev_discrete
J 0
(-1100 4450);
PAINT ORANGE (-1100 4450);
DISPLAY INVISIBLE (-1100 4450);
FORCEPROP 2 LAST CDS_SEC 1
J 0
(-1050 4650);
PAINT MONO (-1050 4650);
DISPLAY INVISIBLE (-1050 4650);
FORCEPROP 2 LAST $SEC 1
J 0
(-1050 4650);
PAINT MONO (-1050 4650);
DISPLAY INVISIBLE (-1050 4650);
FORCEPROP 1 LAST PATH I69
J 0
(-1050 4600);
DISPLAY 0.978723 (-1050 4600);
PAINT WHITE (-1050 4600);
DISPLAY INVISIBLE (-1050 4600);
FORCEPROP 2 LAST ROOM PVCCIN_CPU0_DECAP_VR
J 0
(-1050 4600);
DISPLAY 1.021277 (-1050 4600);
PAINT ORANGE (-1050 4600);
DISPLAY INVISIBLE (-1050 4600);
FORCEADD CAP_A..1
(-1400 4475);
FORCEPROP 1 LAST LOCATION C5D37
J 0
(-1350 4575);
DISPLAY 0.617021 (-1350 4575);
PAINT AQUA (-1350 4575);
FORCEPROP 1 LAST PART_NUMBER E15431-004
J 0
(-1350 4325);
DISPLAY 0.617021 (-1350 4325);
PAINT BLUE (-1350 4325);
FORCEPROP 1 LAST VALUE 22.0UF
J 0
(-1350 4525);
DISPLAY 0.617021 (-1350 4525);
PAINT SKYBLUE (-1350 4525);
FORCEPROP 1 LAST TOLERANCE 20%
J 0
(-1350 4425);
DISPLAY 0.617021 (-1350 4425);
PAINT SKYBLUE (-1350 4425);
FORCEPROP 1 LAST PACK_TYPE 0603V
J 0
(-1350 4275);
DISPLAY 0.617021 (-1350 4275);
PAINT SKYBLUE (-1350 4275);
FORCEPROP 1 LAST VOLTAGE 4V
J 0
(-1350 4475);
DISPLAY 0.617021 (-1350 4475);
PAINT SKYBLUE (-1350 4475);
FORCEPROP 1 LAST MATERIAL X6S
J 0
(-1350 4375);
DISPLAY 0.617021 (-1350 4375);
PAINT SKYBLUE (-1350 4375);
FORCEPROP 1 LASTPIN (-1400 4575) $PN 1
J 0
(-1390 4555);
DISPLAY 0.617021 (-1390 4555);
PAINT GREEN (-1390 4555);
FORCEPROP 1 LASTPIN (-1400 4375) $PN 2
J 0
(-1390 4355);
DISPLAY 0.617021 (-1390 4355);
PAINT GREEN (-1390 4355);
FORCEPROP 2 LAST CDS_LOCATION C5D37
J 0
(-1350 4575);
DISPLAY 0.617021 (-1350 4575);
PAINT AQUA (-1350 4575);
DISPLAY INVISIBLE (-1350 4575);
FORCEPROP 2 LAST BOM_COST PROC_SOCKET
J 0
(-1350 4675);
DISPLAY 1.021277 (-1350 4675);
PAINT ORANGE (-1350 4675);
DISPLAY INVISIBLE (-1350 4675);
FORCEPROP 2 LAST CDS_LIB dev_discrete
J 0
(-1400 4475);
PAINT ORANGE (-1400 4475);
DISPLAY INVISIBLE (-1400 4475);
FORCEPROP 2 LAST CDS_SEC 1
J 0
(-1350 4675);
PAINT MONO (-1350 4675);
DISPLAY INVISIBLE (-1350 4675);
FORCEPROP 2 LAST $SEC 1
J 0
(-1350 4675);
PAINT MONO (-1350 4675);
DISPLAY INVISIBLE (-1350 4675);
FORCEPROP 1 LAST PATH I70
J 0
(-1350 4625);
DISPLAY 0.978723 (-1350 4625);
PAINT WHITE (-1350 4625);
DISPLAY INVISIBLE (-1350 4625);
FORCEPROP 2 LAST ROOM PVCCIN_CPU0_DECAP_VR
J 0
(-1350 4625);
DISPLAY 1.021277 (-1350 4625);
PAINT ORANGE (-1350 4625);
DISPLAY INVISIBLE (-1350 4625);
FORCEADD GND..1
(-525 4150);
FORCEPROP 3 LASTPIN (-525 4200) SIG_NAME GND\g
J 0
(-515 4210);
DISPLAY 0.659574 (-515 4210);
PAINT MONO (-515 4210);
DISPLAY INVISIBLE (-515 4210);
FORCEPROP 1 LAST VOLTAGE 0
J 0
(-525 4150);
PAINT SKYBLUE (-525 4150);
DISPLAY INVISIBLE (-525 4150);
FORCEPROP 2 LAST CDS_LIB mstr_symbols
J 0
(-525 4150);
PAINT ORANGE (-525 4150);
DISPLAY INVISIBLE (-525 4150);
FORCEPROP 1 LAST SIZE 1B
J 0
(-450 4100);
DISPLAY 0.893617 (-450 4100);
PAINT GREEN (-450 4100);
DISPLAY INVISIBLE (-450 4100);
FORCEPROP 1 LAST BODY_TYPE PLUMBING
J 0
(-570 4107);
DISPLAY 0.340426 (-570 4107);
PAINT GREEN (-570 4107);
DISPLAY INVISIBLE (-570 4107);
FORCEPROP 1 LAST PATH I71
J 0
(-450 4150);
DISPLAY 0.872340 (-450 4150);
PAINT AQUA (-450 4150);
DISPLAY INVISIBLE (-450 4150);
FORCEPROP 1 LAST HDL_POWER GND
J 0
(-525 4300);
DISPLAY 0.893617 (-525 4300);
PAINT GREEN (-525 4300);
DISPLAY INVISIBLE (-525 4300);
FORCEADD CAP_A..1
(-3375 3800);
FORCEPROP 1 LAST LOCATION C6D7
J 0
(-3325 3900);
DISPLAY 0.617021 (-3325 3900);
PAINT AQUA (-3325 3900);
FORCEPROP 1 LAST PART_NUMBER E15431-004
J 0
(-3325 3650);
DISPLAY 0.617021 (-3325 3650);
PAINT BLUE (-3325 3650);
FORCEPROP 1 LAST VALUE 22.0UF
J 0
(-3325 3850);
DISPLAY 0.617021 (-3325 3850);
PAINT SKYBLUE (-3325 3850);
FORCEPROP 1 LAST TOLERANCE 20%
J 0
(-3325 3750);
DISPLAY 0.617021 (-3325 3750);
PAINT SKYBLUE (-3325 3750);
FORCEPROP 1 LAST PACK_TYPE 0603V
J 0
(-3325 3600);
DISPLAY 0.617021 (-3325 3600);
PAINT SKYBLUE (-3325 3600);
FORCEPROP 1 LAST VOLTAGE 4V
J 0
(-3325 3800);
DISPLAY 0.617021 (-3325 3800);
PAINT SKYBLUE (-3325 3800);
FORCEPROP 1 LAST MATERIAL X6S
J 0
(-3325 3700);
DISPLAY 0.617021 (-3325 3700);
PAINT SKYBLUE (-3325 3700);
FORCEPROP 1 LASTPIN (-3375 3900) $PN 1
J 0
(-3365 3880);
DISPLAY 0.617021 (-3365 3880);
PAINT GREEN (-3365 3880);
FORCEPROP 1 LASTPIN (-3375 3700) $PN 2
J 0
(-3365 3680);
DISPLAY 0.617021 (-3365 3680);
PAINT GREEN (-3365 3680);
FORCEPROP 2 LAST CDS_LOCATION C6D7
J 0
(-3325 3900);
DISPLAY 0.617021 (-3325 3900);
PAINT AQUA (-3325 3900);
DISPLAY INVISIBLE (-3325 3900);
FORCEPROP 2 LAST BOM_COST PROC_SOCKET
J 0
(-3325 4000);
DISPLAY 1.021277 (-3325 4000);
PAINT ORANGE (-3325 4000);
DISPLAY INVISIBLE (-3325 4000);
FORCEPROP 2 LAST CDS_LIB dev_discrete
J 0
(-3375 3800);
PAINT ORANGE (-3375 3800);
DISPLAY INVISIBLE (-3375 3800);
FORCEPROP 2 LAST CDS_SEC 1
J 0
(-3325 4000);
PAINT MONO (-3325 4000);
DISPLAY INVISIBLE (-3325 4000);
FORCEPROP 2 LAST $SEC 1
J 0
(-3325 4000);
PAINT MONO (-3325 4000);
DISPLAY INVISIBLE (-3325 4000);
FORCEPROP 1 LAST PATH I72
J 0
(-3325 3950);
DISPLAY 0.978723 (-3325 3950);
PAINT WHITE (-3325 3950);
DISPLAY INVISIBLE (-3325 3950);
FORCEPROP 2 LAST ROOM PVCCIN_CPU0_DECAP_VR
J 0
(-3325 3950);
DISPLAY 1.021277 (-3325 3950);
PAINT ORANGE (-3325 3950);
DISPLAY INVISIBLE (-3325 3950);
FORCEADD GND..1
(-2850 3500);
FORCEPROP 3 LASTPIN (-2850 3550) SIG_NAME GND\g
J 0
(-2840 3560);
DISPLAY 0.659574 (-2840 3560);
PAINT MONO (-2840 3560);
DISPLAY INVISIBLE (-2840 3560);
FORCEPROP 1 LAST VOLTAGE 0
J 0
(-2850 3500);
PAINT SKYBLUE (-2850 3500);
DISPLAY INVISIBLE (-2850 3500);
FORCEPROP 2 LAST CDS_LIB mstr_symbols
J 0
(-2850 3500);
PAINT ORANGE (-2850 3500);
DISPLAY INVISIBLE (-2850 3500);
FORCEPROP 1 LAST SIZE 1B
J 0
(-2775 3450);
DISPLAY 0.893617 (-2775 3450);
PAINT GREEN (-2775 3450);
DISPLAY INVISIBLE (-2775 3450);
FORCEPROP 1 LAST BODY_TYPE PLUMBING
J 0
(-2895 3457);
DISPLAY 0.340426 (-2895 3457);
PAINT GREEN (-2895 3457);
DISPLAY INVISIBLE (-2895 3457);
FORCEPROP 1 LAST PATH I73
J 0
(-2775 3500);
DISPLAY 0.872340 (-2775 3500);
PAINT AQUA (-2775 3500);
DISPLAY INVISIBLE (-2775 3500);
FORCEPROP 1 LAST HDL_POWER GND
J 0
(-2850 3650);
DISPLAY 0.893617 (-2850 3650);
PAINT GREEN (-2850 3650);
DISPLAY INVISIBLE (-2850 3650);
FORCEADD CAP_A..1
(-3600 3800);
FORCEPROP 1 LAST LOCATION C6D4
J 0
(-3550 3900);
DISPLAY 0.617021 (-3550 3900);
PAINT AQUA (-3550 3900);
FORCEPROP 1 LAST PART_NUMBER E15431-004
J 0
(-3550 3650);
DISPLAY 0.617021 (-3550 3650);
PAINT BLUE (-3550 3650);
FORCEPROP 1 LAST VALUE 22.0UF
J 0
(-3550 3850);
DISPLAY 0.617021 (-3550 3850);
PAINT SKYBLUE (-3550 3850);
FORCEPROP 1 LAST TOLERANCE 20%
J 0
(-3550 3750);
DISPLAY 0.617021 (-3550 3750);
PAINT SKYBLUE (-3550 3750);
FORCEPROP 1 LAST PACK_TYPE 0603V
J 0
(-3550 3600);
DISPLAY 0.617021 (-3550 3600);
PAINT SKYBLUE (-3550 3600);
FORCEPROP 1 LAST VOLTAGE 4V
J 0
(-3550 3800);
DISPLAY 0.617021 (-3550 3800);
PAINT SKYBLUE (-3550 3800);
FORCEPROP 1 LAST MATERIAL X6S
J 0
(-3550 3700);
DISPLAY 0.617021 (-3550 3700);
PAINT SKYBLUE (-3550 3700);
FORCEPROP 1 LASTPIN (-3600 3900) $PN 1
J 0
(-3590 3880);
DISPLAY 0.617021 (-3590 3880);
PAINT GREEN (-3590 3880);
FORCEPROP 1 LASTPIN (-3600 3700) $PN 2
J 0
(-3590 3680);
DISPLAY 0.617021 (-3590 3680);
PAINT GREEN (-3590 3680);
FORCEPROP 2 LAST CDS_LOCATION C6D4
J 0
(-3550 3900);
DISPLAY 0.617021 (-3550 3900);
PAINT AQUA (-3550 3900);
DISPLAY INVISIBLE (-3550 3900);
FORCEPROP 2 LAST BOM_COST PROC_SOCKET
J 0
(-3550 4000);
DISPLAY 1.021277 (-3550 4000);
PAINT ORANGE (-3550 4000);
DISPLAY INVISIBLE (-3550 4000);
FORCEPROP 2 LAST CDS_LIB dev_discrete
J 0
(-3600 3800);
PAINT ORANGE (-3600 3800);
DISPLAY INVISIBLE (-3600 3800);
FORCEPROP 2 LAST CDS_SEC 1
J 0
(-3550 4000);
PAINT MONO (-3550 4000);
DISPLAY INVISIBLE (-3550 4000);
FORCEPROP 2 LAST $SEC 1
J 0
(-3550 4000);
PAINT MONO (-3550 4000);
DISPLAY INVISIBLE (-3550 4000);
FORCEPROP 1 LAST PATH I74
J 0
(-3550 3950);
DISPLAY 0.978723 (-3550 3950);
PAINT WHITE (-3550 3950);
DISPLAY INVISIBLE (-3550 3950);
FORCEPROP 2 LAST ROOM PVCCIN_CPU0_DECAP_VR
J 0
(-3550 3950);
DISPLAY 1.021277 (-3550 3950);
PAINT ORANGE (-3550 3950);
DISPLAY INVISIBLE (-3550 3950);
FORCEADD CAP_A..1
(-1700 4450);
FORCEPROP 1 LAST LOCATION C6D5
J 0
(-1650 4550);
DISPLAY 0.617021 (-1650 4550);
PAINT AQUA (-1650 4550);
FORCEPROP 1 LAST PART_NUMBER E15431-004
J 0
(-1650 4300);
DISPLAY 0.617021 (-1650 4300);
PAINT BLUE (-1650 4300);
FORCEPROP 1 LAST VALUE 22.0UF
J 0
(-1650 4500);
DISPLAY 0.617021 (-1650 4500);
PAINT SKYBLUE (-1650 4500);
FORCEPROP 1 LAST TOLERANCE 20%
J 0
(-1650 4400);
DISPLAY 0.617021 (-1650 4400);
PAINT SKYBLUE (-1650 4400);
FORCEPROP 1 LAST PACK_TYPE 0603V
J 0
(-1650 4250);
DISPLAY 0.617021 (-1650 4250);
PAINT SKYBLUE (-1650 4250);
FORCEPROP 1 LAST VOLTAGE 4V
J 0
(-1650 4450);
DISPLAY 0.617021 (-1650 4450);
PAINT SKYBLUE (-1650 4450);
FORCEPROP 1 LAST MATERIAL X6S
J 0
(-1650 4350);
DISPLAY 0.617021 (-1650 4350);
PAINT SKYBLUE (-1650 4350);
FORCEPROP 1 LASTPIN (-1700 4550) $PN 1
J 0
(-1690 4530);
DISPLAY 0.617021 (-1690 4530);
PAINT GREEN (-1690 4530);
FORCEPROP 1 LASTPIN (-1700 4350) $PN 2
J 0
(-1690 4330);
DISPLAY 0.617021 (-1690 4330);
PAINT GREEN (-1690 4330);
FORCEPROP 2 LAST CDS_LOCATION C6D5
J 0
(-1650 4550);
DISPLAY 0.617021 (-1650 4550);
PAINT AQUA (-1650 4550);
DISPLAY INVISIBLE (-1650 4550);
FORCEPROP 2 LAST BOM_COST PROC_SOCKET
J 0
(-1650 4650);
DISPLAY 1.021277 (-1650 4650);
PAINT ORANGE (-1650 4650);
DISPLAY INVISIBLE (-1650 4650);
FORCEPROP 2 LAST CDS_LIB dev_discrete
J 0
(-1700 4450);
PAINT ORANGE (-1700 4450);
DISPLAY INVISIBLE (-1700 4450);
FORCEPROP 2 LAST CDS_SEC 1
J 0
(-1650 4650);
PAINT MONO (-1650 4650);
DISPLAY INVISIBLE (-1650 4650);
FORCEPROP 2 LAST $SEC 1
J 0
(-1650 4650);
PAINT MONO (-1650 4650);
DISPLAY INVISIBLE (-1650 4650);
FORCEPROP 1 LAST PATH I75
J 0
(-1650 4600);
DISPLAY 0.978723 (-1650 4600);
PAINT WHITE (-1650 4600);
DISPLAY INVISIBLE (-1650 4600);
FORCEPROP 2 LAST ROOM PVCCIN_CPU0_DECAP_VR
J 0
(-1650 4600);
DISPLAY 1.021277 (-1650 4600);
PAINT ORANGE (-1650 4600);
DISPLAY INVISIBLE (-1650 4600);
FORCEADD CAP_A..1
(-2000 4475);
FORCEPROP 1 LAST LOCATION C6D2
J 0
(-1950 4575);
DISPLAY 0.617021 (-1950 4575);
PAINT AQUA (-1950 4575);
FORCEPROP 1 LAST PART_NUMBER E15431-004
J 0
(-1950 4325);
DISPLAY 0.617021 (-1950 4325);
PAINT BLUE (-1950 4325);
FORCEPROP 1 LAST VALUE 22.0UF
J 0
(-1950 4525);
DISPLAY 0.617021 (-1950 4525);
PAINT SKYBLUE (-1950 4525);
FORCEPROP 1 LAST TOLERANCE 20%
J 0
(-1950 4425);
DISPLAY 0.617021 (-1950 4425);
PAINT SKYBLUE (-1950 4425);
FORCEPROP 1 LAST PACK_TYPE 0603V
J 0
(-1950 4275);
DISPLAY 0.617021 (-1950 4275);
PAINT SKYBLUE (-1950 4275);
FORCEPROP 1 LAST VOLTAGE 4V
J 0
(-1950 4475);
DISPLAY 0.617021 (-1950 4475);
PAINT SKYBLUE (-1950 4475);
FORCEPROP 1 LAST MATERIAL X6S
J 0
(-1950 4375);
DISPLAY 0.617021 (-1950 4375);
PAINT SKYBLUE (-1950 4375);
FORCEPROP 1 LASTPIN (-2000 4575) $PN 1
J 0
(-1990 4555);
DISPLAY 0.617021 (-1990 4555);
PAINT GREEN (-1990 4555);
FORCEPROP 1 LASTPIN (-2000 4375) $PN 2
J 0
(-1990 4355);
DISPLAY 0.617021 (-1990 4355);
PAINT GREEN (-1990 4355);
FORCEPROP 2 LAST CDS_LOCATION C6D2
J 0
(-1950 4575);
DISPLAY 0.617021 (-1950 4575);
PAINT AQUA (-1950 4575);
DISPLAY INVISIBLE (-1950 4575);
FORCEPROP 2 LAST BOM_COST PROC_SOCKET
J 0
(-1950 4675);
DISPLAY 1.021277 (-1950 4675);
PAINT ORANGE (-1950 4675);
DISPLAY INVISIBLE (-1950 4675);
FORCEPROP 2 LAST CDS_LIB dev_discrete
J 0
(-2000 4475);
PAINT ORANGE (-2000 4475);
DISPLAY INVISIBLE (-2000 4475);
FORCEPROP 2 LAST CDS_SEC 1
J 0
(-1950 4675);
PAINT MONO (-1950 4675);
DISPLAY INVISIBLE (-1950 4675);
FORCEPROP 2 LAST $SEC 1
J 0
(-1950 4675);
PAINT MONO (-1950 4675);
DISPLAY INVISIBLE (-1950 4675);
FORCEPROP 1 LAST PATH I77
J 0
(-1950 4625);
DISPLAY 0.978723 (-1950 4625);
PAINT WHITE (-1950 4625);
DISPLAY INVISIBLE (-1950 4625);
FORCEPROP 2 LAST ROOM PVCCIN_CPU0_DECAP_VR
J 0
(-1950 4625);
DISPLAY 1.021277 (-1950 4625);
PAINT ORANGE (-1950 4625);
DISPLAY INVISIBLE (-1950 4625);
FORCEADD PVCCIO_CPU0..1
(-4075 4075);
FORCEPROP 3 LASTPIN (-4075 4025) SIG_NAME PVCCIO_CPU0\g
J 0
(-4065 4035);
DISPLAY 0.659574 (-4065 4035);
PAINT MONO (-4065 4035);
DISPLAY INVISIBLE (-4065 4035);
FORCEPROP 1 LAST VOLTAGE 1.1V
J 0
(-4120 4032);
DISPLAY 0.340426 (-4120 4032);
PAINT SKYBLUE (-4120 4032);
DISPLAY INVISIBLE (-4120 4032);
FORCEPROP 2 LAST CDS_LIB mstr_symbols
J 0
(-4075 4075);
PAINT ORANGE (-4075 4075);
DISPLAY INVISIBLE (-4075 4075);
FORCEPROP 1 LAST BODY_TYPE PLUMBING
J 0
(-4120 4032);
DISPLAY 0.340426 (-4120 4032);
PAINT GREEN (-4120 4032);
DISPLAY INVISIBLE (-4120 4032);
FORCEPROP 1 LAST PATH I79
J 0
(-4025 4100);
DISPLAY 0.872340 (-4025 4100);
PAINT AQUA (-4025 4100);
DISPLAY INVISIBLE (-4025 4100);
FORCEPROP 1 LAST HDL_POWER PVCCIO_CPU0
J 1
(-4075 4125);
DISPLAY 0.872340 (-4075 4125);
PAINT GREEN (-4075 4125);
DISPLAY INVISIBLE (-4075 4125);
FORCEADD CAP..1
(-3275 2175);
FORCEPROP 1 LAST LOCATION C4P3
J 0
(-3225 2275);
DISPLAY 0.617021 (-3225 2275);
PAINT AQUA (-3225 2275);
FORCEPROP 1 LAST PART_NUMBER C95333-006
R 1
J 0
(-3325 2000);
DISPLAY 0.617021 (-3325 2000);
PAINT BLUE (-3325 2000);
FORCEPROP 1 LAST VALUE 47UF
J 0
(-3225 2225);
DISPLAY 0.617021 (-3225 2225);
PAINT SKYBLUE (-3225 2225);
FORCEPROP 1 LAST TOLERANCE 20%
J 0
(-3225 2125);
DISPLAY 0.617021 (-3225 2125);
PAINT SKYBLUE (-3225 2125);
FORCEPROP 1 LAST PACK_TYPE 0805
J 0
(-3225 2025);
DISPLAY 0.617021 (-3225 2025);
PAINT SKYBLUE (-3225 2025);
FORCEPROP 1 LASTPIN (-3275 2075) $PN 2
J 0
(-3265 2055);
DISPLAY 0.617021 (-3265 2055);
PAINT GREEN (-3265 2055);
FORCEPROP 1 LASTPIN (-3275 2275) $PN 1
J 0
(-3265 2255);
DISPLAY 0.617021 (-3265 2255);
PAINT GREEN (-3265 2255);
FORCEPROP 1 LAST VOLTAGE 4V
J 0
(-3225 2175);
PAINT SKYBLUE (-3225 2175);
DISPLAY INVISIBLE (-3225 2175);
FORCEPROP 1 LAST MATERIAL X6S
J 0
(-3225 2075);
PAINT SKYBLUE (-3225 2075);
DISPLAY INVISIBLE (-3225 2075);
FORCEPROP 2 LAST CDS_LIB mstr_discrete
J 0
(-3275 2175);
PAINT ORANGE (-3275 2175);
DISPLAY INVISIBLE (-3275 2175);
FORCEPROP 2 LAST BOM_COST PROC_SOCKET
J 0
(-3225 2375);
DISPLAY 1.021277 (-3225 2375);
PAINT ORANGE (-3225 2375);
DISPLAY INVISIBLE (-3225 2375);
FORCEPROP 2 LAST CDS_SEC 1
J 0
(-3225 2375);
DISPLAY 1.021277 (-3225 2375);
PAINT ORANGE (-3225 2375);
DISPLAY INVISIBLE (-3225 2375);
FORCEPROP 2 LAST $SEC 1
J 0
(-3225 2375);
DISPLAY 0.680851 (-3225 2375);
PAINT MONO (-3225 2375);
DISPLAY INVISIBLE (-3225 2375);
FORCEPROP 2 LAST CDS_LOCATION C4P3
J 0
(-3225 2275);
DISPLAY 0.617021 (-3225 2275);
PAINT AQUA (-3225 2275);
DISPLAY INVISIBLE (-3225 2275);
FORCEPROP 1 LAST PATH I8
J 0
(-3225 2325);
DISPLAY 0.978723 (-3225 2325);
PAINT WHITE (-3225 2325);
DISPLAY INVISIBLE (-3225 2325);
FORCEPROP 2 LAST ROOM PVCCIN_CPU0_DECAP_VR
J 0
(-3225 2325);
DISPLAY 1.021277 (-3225 2325);
PAINT ORANGE (-3225 2325);
DISPLAY INVISIBLE (-3225 2325);
FORCEADD CAP_A..1
(-3825 3800);
FORCEPROP 1 LAST LOCATION C6D3
J 0
(-3775 3900);
DISPLAY 0.617021 (-3775 3900);
PAINT AQUA (-3775 3900);
FORCEPROP 1 LAST PART_NUMBER E15431-004
J 0
(-3775 3650);
DISPLAY 0.617021 (-3775 3650);
PAINT BLUE (-3775 3650);
FORCEPROP 1 LAST VALUE 22.0UF
J 0
(-3775 3850);
DISPLAY 0.617021 (-3775 3850);
PAINT SKYBLUE (-3775 3850);
FORCEPROP 1 LAST TOLERANCE 20%
J 0
(-3775 3750);
DISPLAY 0.617021 (-3775 3750);
PAINT SKYBLUE (-3775 3750);
FORCEPROP 1 LAST PACK_TYPE 0603V
J 0
(-3775 3600);
DISPLAY 0.617021 (-3775 3600);
PAINT SKYBLUE (-3775 3600);
FORCEPROP 1 LAST VOLTAGE 4V
J 0
(-3775 3800);
DISPLAY 0.617021 (-3775 3800);
PAINT SKYBLUE (-3775 3800);
FORCEPROP 1 LAST MATERIAL X6S
J 0
(-3775 3700);
DISPLAY 0.617021 (-3775 3700);
PAINT SKYBLUE (-3775 3700);
FORCEPROP 1 LASTPIN (-3825 3900) $PN 1
J 0
(-3815 3880);
DISPLAY 0.617021 (-3815 3880);
PAINT GREEN (-3815 3880);
FORCEPROP 1 LASTPIN (-3825 3700) $PN 2
J 0
(-3815 3680);
DISPLAY 0.617021 (-3815 3680);
PAINT GREEN (-3815 3680);
FORCEPROP 2 LAST CDS_LOCATION C6D3
J 0
(-3775 3900);
DISPLAY 0.617021 (-3775 3900);
PAINT AQUA (-3775 3900);
DISPLAY INVISIBLE (-3775 3900);
FORCEPROP 2 LAST BOM_COST PROC_SOCKET
J 0
(-3775 4000);
DISPLAY 1.021277 (-3775 4000);
PAINT ORANGE (-3775 4000);
DISPLAY INVISIBLE (-3775 4000);
FORCEPROP 2 LAST CDS_LIB dev_discrete
J 0
(-3825 3800);
PAINT ORANGE (-3825 3800);
DISPLAY INVISIBLE (-3825 3800);
FORCEPROP 2 LAST CDS_SEC 1
J 0
(-3775 4000);
PAINT MONO (-3775 4000);
DISPLAY INVISIBLE (-3775 4000);
FORCEPROP 2 LAST $SEC 1
J 0
(-3775 4000);
PAINT MONO (-3775 4000);
DISPLAY INVISIBLE (-3775 4000);
FORCEPROP 1 LAST PATH I80
J 0
(-3775 3950);
DISPLAY 0.978723 (-3775 3950);
PAINT WHITE (-3775 3950);
DISPLAY INVISIBLE (-3775 3950);
FORCEPROP 2 LAST ROOM PVCCIN_CPU0_DECAP_VR
J 0
(-3775 3950);
DISPLAY 1.021277 (-3775 3950);
PAINT ORANGE (-3775 3950);
DISPLAY INVISIBLE (-3775 3950);
FORCEADD CAP_A..1
(-4075 3775);
FORCEPROP 1 LAST LOCATION C6D6
J 0
(-4025 3875);
DISPLAY 0.617021 (-4025 3875);
PAINT AQUA (-4025 3875);
FORCEPROP 1 LAST PART_NUMBER E15431-004
J 0
(-4025 3625);
DISPLAY 0.617021 (-4025 3625);
PAINT BLUE (-4025 3625);
FORCEPROP 1 LAST VALUE 22.0UF
J 0
(-4025 3825);
DISPLAY 0.617021 (-4025 3825);
PAINT SKYBLUE (-4025 3825);
FORCEPROP 1 LAST TOLERANCE 20%
J 0
(-4025 3725);
DISPLAY 0.617021 (-4025 3725);
PAINT SKYBLUE (-4025 3725);
FORCEPROP 1 LAST PACK_TYPE 0603V
J 0
(-4025 3575);
DISPLAY 0.617021 (-4025 3575);
PAINT SKYBLUE (-4025 3575);
FORCEPROP 1 LAST VOLTAGE 4V
J 0
(-4025 3775);
DISPLAY 0.617021 (-4025 3775);
PAINT SKYBLUE (-4025 3775);
FORCEPROP 1 LAST MATERIAL X6S
J 0
(-4025 3675);
DISPLAY 0.617021 (-4025 3675);
PAINT SKYBLUE (-4025 3675);
FORCEPROP 1 LASTPIN (-4075 3875) $PN 1
J 0
(-4065 3855);
DISPLAY 0.617021 (-4065 3855);
PAINT GREEN (-4065 3855);
FORCEPROP 1 LASTPIN (-4075 3675) $PN 2
J 0
(-4065 3655);
DISPLAY 0.617021 (-4065 3655);
PAINT GREEN (-4065 3655);
FORCEPROP 2 LAST CDS_LOCATION C6D6
J 0
(-4025 3875);
DISPLAY 0.617021 (-4025 3875);
PAINT AQUA (-4025 3875);
DISPLAY INVISIBLE (-4025 3875);
FORCEPROP 2 LAST BOM_COST PROC_SOCKET
J 0
(-4025 3975);
DISPLAY 1.021277 (-4025 3975);
PAINT ORANGE (-4025 3975);
DISPLAY INVISIBLE (-4025 3975);
FORCEPROP 2 LAST CDS_LIB dev_discrete
J 0
(-4075 3775);
PAINT ORANGE (-4075 3775);
DISPLAY INVISIBLE (-4075 3775);
FORCEPROP 2 LAST CDS_SEC 1
J 0
(-4025 3975);
PAINT MONO (-4025 3975);
DISPLAY INVISIBLE (-4025 3975);
FORCEPROP 2 LAST $SEC 1
J 0
(-4025 3975);
PAINT MONO (-4025 3975);
DISPLAY INVISIBLE (-4025 3975);
FORCEPROP 1 LAST PATH I81
J 0
(-4025 3925);
DISPLAY 0.978723 (-4025 3925);
PAINT WHITE (-4025 3925);
DISPLAY INVISIBLE (-4025 3925);
FORCEPROP 2 LAST ROOM PVCCIN_CPU0_DECAP_VR
J 0
(-4025 3925);
DISPLAY 1.021277 (-4025 3925);
PAINT ORANGE (-4025 3925);
DISPLAY INVISIBLE (-4025 3925);
FORCEADD CAP_A..1
(-2825 4475);
FORCEPROP 1 LAST LOCATION C5D51
J 0
(-2775 4575);
DISPLAY 0.617021 (-2775 4575);
PAINT AQUA (-2775 4575);
FORCEPROP 1 LAST PART_NUMBER E15431-004
J 0
(-2775 4325);
DISPLAY 0.617021 (-2775 4325);
PAINT BLUE (-2775 4325);
FORCEPROP 1 LAST VALUE 22.0UF
J 0
(-2775 4525);
DISPLAY 0.617021 (-2775 4525);
PAINT SKYBLUE (-2775 4525);
FORCEPROP 1 LAST TOLERANCE 20%
J 0
(-2775 4425);
DISPLAY 0.617021 (-2775 4425);
PAINT SKYBLUE (-2775 4425);
FORCEPROP 1 LAST PACK_TYPE 0603V
J 0
(-2775 4275);
DISPLAY 0.617021 (-2775 4275);
PAINT SKYBLUE (-2775 4275);
FORCEPROP 1 LAST VOLTAGE 4V
J 0
(-2775 4475);
DISPLAY 0.617021 (-2775 4475);
PAINT SKYBLUE (-2775 4475);
FORCEPROP 1 LAST MATERIAL X6S
J 0
(-2775 4375);
DISPLAY 0.617021 (-2775 4375);
PAINT SKYBLUE (-2775 4375);
FORCEPROP 1 LASTPIN (-2825 4575) $PN 1
J 0
(-2815 4555);
DISPLAY 0.617021 (-2815 4555);
PAINT GREEN (-2815 4555);
FORCEPROP 1 LASTPIN (-2825 4375) $PN 2
J 0
(-2815 4355);
DISPLAY 0.617021 (-2815 4355);
PAINT GREEN (-2815 4355);
FORCEPROP 2 LAST CDS_LOCATION C5D51
J 0
(-2775 4575);
DISPLAY 0.617021 (-2775 4575);
PAINT AQUA (-2775 4575);
DISPLAY INVISIBLE (-2775 4575);
FORCEPROP 2 LAST BOM_COST PROC_SOCKET
J 0
(-2775 4675);
DISPLAY 1.021277 (-2775 4675);
PAINT ORANGE (-2775 4675);
DISPLAY INVISIBLE (-2775 4675);
FORCEPROP 2 LAST CDS_LIB dev_discrete
J 0
(-2825 4475);
PAINT ORANGE (-2825 4475);
DISPLAY INVISIBLE (-2825 4475);
FORCEPROP 2 LAST CDS_SEC 1
J 0
(-2775 4675);
PAINT MONO (-2775 4675);
DISPLAY INVISIBLE (-2775 4675);
FORCEPROP 2 LAST $SEC 1
J 0
(-2775 4675);
PAINT MONO (-2775 4675);
DISPLAY INVISIBLE (-2775 4675);
FORCEPROP 1 LAST PATH I83
J 0
(-2775 4625);
DISPLAY 0.978723 (-2775 4625);
PAINT WHITE (-2775 4625);
DISPLAY INVISIBLE (-2775 4625);
FORCEPROP 2 LAST ROOM PVCCIN_CPU0_DECAP_VR
J 0
(-2775 4625);
DISPLAY 1.021277 (-2775 4625);
PAINT ORANGE (-2775 4625);
DISPLAY INVISIBLE (-2775 4625);
FORCEADD CAP_A..1
(-3075 4450);
FORCEPROP 1 LAST LOCATION C5D21
J 0
(-3025 4550);
DISPLAY 0.617021 (-3025 4550);
PAINT AQUA (-3025 4550);
FORCEPROP 1 LAST PART_NUMBER E15431-004
J 0
(-3025 4300);
DISPLAY 0.617021 (-3025 4300);
PAINT BLUE (-3025 4300);
FORCEPROP 1 LAST VALUE 22.0UF
J 0
(-3025 4500);
DISPLAY 0.617021 (-3025 4500);
PAINT SKYBLUE (-3025 4500);
FORCEPROP 1 LAST TOLERANCE 20%
J 0
(-3025 4400);
DISPLAY 0.617021 (-3025 4400);
PAINT SKYBLUE (-3025 4400);
FORCEPROP 1 LAST PACK_TYPE 0603V
J 0
(-3025 4250);
DISPLAY 0.617021 (-3025 4250);
PAINT SKYBLUE (-3025 4250);
FORCEPROP 1 LAST VOLTAGE 4V
J 0
(-3025 4450);
DISPLAY 0.617021 (-3025 4450);
PAINT SKYBLUE (-3025 4450);
FORCEPROP 1 LAST MATERIAL X6S
J 0
(-3025 4350);
DISPLAY 0.617021 (-3025 4350);
PAINT SKYBLUE (-3025 4350);
FORCEPROP 1 LASTPIN (-3075 4550) $PN 1
J 0
(-3065 4530);
DISPLAY 0.617021 (-3065 4530);
PAINT GREEN (-3065 4530);
FORCEPROP 1 LASTPIN (-3075 4350) $PN 2
J 0
(-3065 4330);
DISPLAY 0.617021 (-3065 4330);
PAINT GREEN (-3065 4330);
FORCEPROP 2 LAST CDS_LOCATION C5D21
J 0
(-3025 4550);
DISPLAY 0.617021 (-3025 4550);
PAINT AQUA (-3025 4550);
DISPLAY INVISIBLE (-3025 4550);
FORCEPROP 2 LAST BOM_COST PROC_SOCKET
J 0
(-3025 4650);
DISPLAY 1.021277 (-3025 4650);
PAINT ORANGE (-3025 4650);
DISPLAY INVISIBLE (-3025 4650);
FORCEPROP 2 LAST CDS_LIB dev_discrete
J 0
(-3075 4450);
PAINT ORANGE (-3075 4450);
DISPLAY INVISIBLE (-3075 4450);
FORCEPROP 2 LAST CDS_SEC 1
J 0
(-3025 4650);
PAINT MONO (-3025 4650);
DISPLAY INVISIBLE (-3025 4650);
FORCEPROP 2 LAST $SEC 1
J 0
(-3025 4650);
PAINT MONO (-3025 4650);
DISPLAY INVISIBLE (-3025 4650);
FORCEPROP 1 LAST PATH I88
J 0
(-3025 4600);
DISPLAY 0.978723 (-3025 4600);
PAINT WHITE (-3025 4600);
DISPLAY INVISIBLE (-3025 4600);
FORCEPROP 2 LAST ROOM PVCCIN_CPU0_DECAP_VR
J 0
(-3025 4600);
DISPLAY 1.021277 (-3025 4600);
PAINT ORANGE (-3025 4600);
DISPLAY INVISIBLE (-3025 4600);
FORCEADD CAP_A..1
(-3350 4475);
FORCEPROP 1 LAST LOCATION C5D50
J 0
(-3300 4575);
DISPLAY 0.617021 (-3300 4575);
PAINT AQUA (-3300 4575);
FORCEPROP 1 LAST PART_NUMBER E15431-004
J 0
(-3300 4325);
DISPLAY 0.617021 (-3300 4325);
PAINT BLUE (-3300 4325);
FORCEPROP 1 LAST VALUE 22.0UF
J 0
(-3300 4525);
DISPLAY 0.617021 (-3300 4525);
PAINT SKYBLUE (-3300 4525);
FORCEPROP 1 LAST TOLERANCE 20%
J 0
(-3300 4425);
DISPLAY 0.617021 (-3300 4425);
PAINT SKYBLUE (-3300 4425);
FORCEPROP 1 LAST PACK_TYPE 0603V
J 0
(-3300 4275);
DISPLAY 0.617021 (-3300 4275);
PAINT SKYBLUE (-3300 4275);
FORCEPROP 1 LAST VOLTAGE 4V
J 0
(-3300 4475);
DISPLAY 0.617021 (-3300 4475);
PAINT SKYBLUE (-3300 4475);
FORCEPROP 1 LAST MATERIAL X6S
J 0
(-3300 4375);
DISPLAY 0.617021 (-3300 4375);
PAINT SKYBLUE (-3300 4375);
FORCEPROP 1 LASTPIN (-3350 4575) $PN 1
J 0
(-3340 4555);
DISPLAY 0.617021 (-3340 4555);
PAINT GREEN (-3340 4555);
FORCEPROP 1 LASTPIN (-3350 4375) $PN 2
J 0
(-3340 4355);
DISPLAY 0.617021 (-3340 4355);
PAINT GREEN (-3340 4355);
FORCEPROP 2 LAST CDS_LOCATION C5D50
J 0
(-3300 4575);
DISPLAY 0.617021 (-3300 4575);
PAINT AQUA (-3300 4575);
DISPLAY INVISIBLE (-3300 4575);
FORCEPROP 2 LAST BOM_COST PROC_SOCKET
J 0
(-3300 4675);
DISPLAY 1.021277 (-3300 4675);
PAINT ORANGE (-3300 4675);
DISPLAY INVISIBLE (-3300 4675);
FORCEPROP 2 LAST CDS_LIB dev_discrete
J 0
(-3350 4475);
PAINT ORANGE (-3350 4475);
DISPLAY INVISIBLE (-3350 4475);
FORCEPROP 2 LAST CDS_SEC 1
J 0
(-3300 4675);
PAINT MONO (-3300 4675);
DISPLAY INVISIBLE (-3300 4675);
FORCEPROP 2 LAST $SEC 1
J 0
(-3300 4675);
PAINT MONO (-3300 4675);
DISPLAY INVISIBLE (-3300 4675);
FORCEPROP 1 LAST PATH I89
J 0
(-3300 4625);
DISPLAY 0.978723 (-3300 4625);
PAINT WHITE (-3300 4625);
DISPLAY INVISIBLE (-3300 4625);
FORCEPROP 2 LAST ROOM PVCCIN_CPU0_DECAP_VR
J 0
(-3300 4625);
DISPLAY 1.021277 (-3300 4625);
PAINT ORANGE (-3300 4625);
DISPLAY INVISIBLE (-3300 4625);
FORCEADD CAP..1
(-3550 2175);
FORCEPROP 1 LAST LOCATION C4P7
J 0
(-3500 2275);
DISPLAY 0.617021 (-3500 2275);
PAINT AQUA (-3500 2275);
FORCEPROP 1 LAST PART_NUMBER C95333-006
R 1
J 0
(-3600 2000);
DISPLAY 0.617021 (-3600 2000);
PAINT BLUE (-3600 2000);
FORCEPROP 1 LAST VALUE 47UF
J 0
(-3500 2225);
DISPLAY 0.617021 (-3500 2225);
PAINT SKYBLUE (-3500 2225);
FORCEPROP 1 LAST TOLERANCE 20%
J 0
(-3500 2125);
DISPLAY 0.617021 (-3500 2125);
PAINT SKYBLUE (-3500 2125);
FORCEPROP 1 LAST PACK_TYPE 0805
J 0
(-3500 2025);
DISPLAY 0.617021 (-3500 2025);
PAINT SKYBLUE (-3500 2025);
FORCEPROP 1 LASTPIN (-3550 2075) $PN 2
J 0
(-3540 2055);
DISPLAY 0.617021 (-3540 2055);
PAINT GREEN (-3540 2055);
FORCEPROP 1 LASTPIN (-3550 2275) $PN 1
J 0
(-3540 2255);
DISPLAY 0.617021 (-3540 2255);
PAINT GREEN (-3540 2255);
FORCEPROP 1 LAST VOLTAGE 4V
J 0
(-3500 2175);
PAINT SKYBLUE (-3500 2175);
DISPLAY INVISIBLE (-3500 2175);
FORCEPROP 1 LAST MATERIAL X6S
J 0
(-3500 2075);
PAINT SKYBLUE (-3500 2075);
DISPLAY INVISIBLE (-3500 2075);
FORCEPROP 2 LAST CDS_LIB mstr_discrete
J 0
(-3550 2175);
PAINT ORANGE (-3550 2175);
DISPLAY INVISIBLE (-3550 2175);
FORCEPROP 2 LAST BOM_COST PROC_SOCKET
J 0
(-3500 2375);
DISPLAY 1.021277 (-3500 2375);
PAINT ORANGE (-3500 2375);
DISPLAY INVISIBLE (-3500 2375);
FORCEPROP 2 LAST CDS_SEC 1
J 0
(-3500 2375);
DISPLAY 1.021277 (-3500 2375);
PAINT ORANGE (-3500 2375);
DISPLAY INVISIBLE (-3500 2375);
FORCEPROP 2 LAST $SEC 1
J 0
(-3500 2375);
DISPLAY 0.680851 (-3500 2375);
PAINT MONO (-3500 2375);
DISPLAY INVISIBLE (-3500 2375);
FORCEPROP 2 LAST CDS_LOCATION C4P7
J 0
(-3500 2275);
DISPLAY 0.617021 (-3500 2275);
PAINT AQUA (-3500 2275);
DISPLAY INVISIBLE (-3500 2275);
FORCEPROP 1 LAST PATH I9
J 0
(-3500 2325);
DISPLAY 0.978723 (-3500 2325);
PAINT WHITE (-3500 2325);
DISPLAY INVISIBLE (-3500 2325);
FORCEPROP 2 LAST ROOM PVCCIN_CPU0_DECAP_VR
J 0
(-3500 2325);
DISPLAY 1.021277 (-3500 2325);
PAINT ORANGE (-3500 2325);
DISPLAY INVISIBLE (-3500 2325);
FORCEADD CAP_A..1
(-3625 4475);
FORCEPROP 1 LAST LOCATION C5D48
J 0
(-3575 4575);
DISPLAY 0.617021 (-3575 4575);
PAINT AQUA (-3575 4575);
FORCEPROP 1 LAST PART_NUMBER E15431-004
J 0
(-3575 4325);
DISPLAY 0.617021 (-3575 4325);
PAINT BLUE (-3575 4325);
FORCEPROP 1 LAST VALUE 22.0UF
J 0
(-3575 4525);
DISPLAY 0.617021 (-3575 4525);
PAINT SKYBLUE (-3575 4525);
FORCEPROP 1 LAST TOLERANCE 20%
J 0
(-3575 4425);
DISPLAY 0.617021 (-3575 4425);
PAINT SKYBLUE (-3575 4425);
FORCEPROP 1 LAST PACK_TYPE 0603V
J 0
(-3575 4275);
DISPLAY 0.617021 (-3575 4275);
PAINT SKYBLUE (-3575 4275);
FORCEPROP 1 LAST VOLTAGE 4V
J 0
(-3575 4475);
DISPLAY 0.617021 (-3575 4475);
PAINT SKYBLUE (-3575 4475);
FORCEPROP 1 LAST MATERIAL X6S
J 0
(-3575 4375);
DISPLAY 0.617021 (-3575 4375);
PAINT SKYBLUE (-3575 4375);
FORCEPROP 1 LASTPIN (-3625 4575) $PN 1
J 0
(-3615 4555);
DISPLAY 0.617021 (-3615 4555);
PAINT GREEN (-3615 4555);
FORCEPROP 1 LASTPIN (-3625 4375) $PN 2
J 0
(-3615 4355);
DISPLAY 0.617021 (-3615 4355);
PAINT GREEN (-3615 4355);
FORCEPROP 2 LAST CDS_LOCATION C5D48
J 0
(-3575 4575);
DISPLAY 0.617021 (-3575 4575);
PAINT AQUA (-3575 4575);
DISPLAY INVISIBLE (-3575 4575);
FORCEPROP 2 LAST BOM_COST PROC_SOCKET
J 0
(-3575 4675);
DISPLAY 1.021277 (-3575 4675);
PAINT ORANGE (-3575 4675);
DISPLAY INVISIBLE (-3575 4675);
FORCEPROP 2 LAST CDS_LIB dev_discrete
J 0
(-3625 4475);
PAINT ORANGE (-3625 4475);
DISPLAY INVISIBLE (-3625 4475);
FORCEPROP 2 LAST CDS_SEC 1
J 0
(-3575 4675);
PAINT MONO (-3575 4675);
DISPLAY INVISIBLE (-3575 4675);
FORCEPROP 2 LAST $SEC 1
J 0
(-3575 4675);
PAINT MONO (-3575 4675);
DISPLAY INVISIBLE (-3575 4675);
FORCEPROP 1 LAST PATH I90
J 0
(-3575 4625);
DISPLAY 0.978723 (-3575 4625);
PAINT WHITE (-3575 4625);
DISPLAY INVISIBLE (-3575 4625);
FORCEPROP 2 LAST ROOM PVCCIN_CPU0_DECAP_VR
J 0
(-3575 4625);
DISPLAY 1.021277 (-3575 4625);
PAINT ORANGE (-3575 4625);
DISPLAY INVISIBLE (-3575 4625);
FORCEADD CAP..1
(-2875 3125);
FORCEPROP 1 LAST LOCATION C5D13
J 0
(-2825 3225);
DISPLAY 0.617021 (-2825 3225);
PAINT AQUA (-2825 3225);
FORCEPROP 1 LAST PART_NUMBER E15431-001
J 0
(-2825 2975);
DISPLAY 0.617021 (-2825 2975);
PAINT BLUE (-2825 2975);
FORCEPROP 1 LAST VALUE 10UF
J 0
(-2825 3175);
DISPLAY 0.617021 (-2825 3175);
PAINT SKYBLUE (-2825 3175);
FORCEPROP 1 LAST TOLERANCE 20%
J 0
(-2825 3075);
DISPLAY 0.617021 (-2825 3075);
PAINT SKYBLUE (-2825 3075);
FORCEPROP 1 LAST PACK_TYPE 0603LF
J 0
(-2825 2925);
DISPLAY 0.617021 (-2825 2925);
PAINT SKYBLUE (-2825 2925);
FORCEPROP 1 LAST VOLTAGE 4V
J 0
(-2825 3125);
DISPLAY 0.617021 (-2825 3125);
PAINT SKYBLUE (-2825 3125);
FORCEPROP 1 LAST MATERIAL X6S
J 0
(-2825 3025);
DISPLAY 0.617021 (-2825 3025);
PAINT SKYBLUE (-2825 3025);
FORCEPROP 1 LASTPIN (-2875 3025) $PN 2
J 0
(-2865 3005);
DISPLAY 0.617021 (-2865 3005);
PAINT GREEN (-2865 3005);
FORCEPROP 1 LASTPIN (-2875 3225) $PN 1
J 0
(-2865 3205);
DISPLAY 0.617021 (-2865 3205);
PAINT GREEN (-2865 3205);
FORCEPROP 2 LAST CDS_LIB mstr_discrete
J 0
(-2875 3125);
PAINT ORANGE (-2875 3125);
DISPLAY INVISIBLE (-2875 3125);
FORCEPROP 2 LAST BOM_COST PROC_SOCKET
J 0
(-2825 3325);
DISPLAY 1.021277 (-2825 3325);
PAINT ORANGE (-2825 3325);
DISPLAY INVISIBLE (-2825 3325);
FORCEPROP 2 LAST CDS_SEC 1
J 0
(-2825 3325);
PAINT MONO (-2825 3325);
DISPLAY INVISIBLE (-2825 3325);
FORCEPROP 2 LAST $SEC 1
J 0
(-2825 3325);
PAINT MONO (-2825 3325);
DISPLAY INVISIBLE (-2825 3325);
FORCEPROP 2 LAST CDS_LOCATION C5D13
J 0
(-2825 3225);
DISPLAY 0.617021 (-2825 3225);
PAINT AQUA (-2825 3225);
DISPLAY INVISIBLE (-2825 3225);
FORCEPROP 1 LAST PATH I91
J 0
(-2825 3275);
DISPLAY 0.978723 (-2825 3275);
PAINT WHITE (-2825 3275);
DISPLAY INVISIBLE (-2825 3275);
FORCEPROP 2 LAST ROOM PVCCIN_CPU0_DECAP_VR
J 0
(-2825 3275);
DISPLAY 1.021277 (-2825 3275);
PAINT ORANGE (-2825 3275);
DISPLAY INVISIBLE (-2825 3275);
FORCEADD GND..1
(-2875 2800);
FORCEPROP 3 LASTPIN (-2875 2850) SIG_NAME GND\g
J 0
(-2865 2860);
DISPLAY 0.659574 (-2865 2860);
PAINT MONO (-2865 2860);
DISPLAY INVISIBLE (-2865 2860);
FORCEPROP 1 LAST VOLTAGE 0
J 0
(-2875 2800);
PAINT SKYBLUE (-2875 2800);
DISPLAY INVISIBLE (-2875 2800);
FORCEPROP 2 LAST CDS_LIB mstr_symbols
J 0
(-2875 2800);
PAINT ORANGE (-2875 2800);
DISPLAY INVISIBLE (-2875 2800);
FORCEPROP 1 LAST SIZE 1B
J 0
(-2800 2750);
DISPLAY 0.893617 (-2800 2750);
PAINT GREEN (-2800 2750);
DISPLAY INVISIBLE (-2800 2750);
FORCEPROP 1 LAST BODY_TYPE PLUMBING
J 0
(-2920 2757);
DISPLAY 0.340426 (-2920 2757);
PAINT GREEN (-2920 2757);
DISPLAY INVISIBLE (-2920 2757);
FORCEPROP 1 LAST PATH I92
J 0
(-2800 2800);
DISPLAY 0.872340 (-2800 2800);
PAINT AQUA (-2800 2800);
DISPLAY INVISIBLE (-2800 2800);
FORCEPROP 1 LAST HDL_POWER GND
J 0
(-2875 2950);
DISPLAY 0.893617 (-2875 2950);
PAINT GREEN (-2875 2950);
DISPLAY INVISIBLE (-2875 2950);
FORCEADD CAP..1
(-3275 3125);
FORCEPROP 1 LAST LOCATION C5D11
J 0
(-3225 3225);
DISPLAY 0.617021 (-3225 3225);
PAINT AQUA (-3225 3225);
FORCEPROP 1 LAST PART_NUMBER E15431-001
J 0
(-3240 2980);
DISPLAY 0.617021 (-3240 2980);
PAINT BLUE (-3240 2980);
FORCEPROP 1 LAST VALUE 10UF
J 0
(-3225 3175);
DISPLAY 0.617021 (-3225 3175);
PAINT SKYBLUE (-3225 3175);
FORCEPROP 1 LAST TOLERANCE 20%
J 0
(-3225 3075);
DISPLAY 0.617021 (-3225 3075);
PAINT SKYBLUE (-3225 3075);
FORCEPROP 1 LAST PACK_TYPE 0603LF
J 0
(-3225 2925);
DISPLAY 0.617021 (-3225 2925);
PAINT SKYBLUE (-3225 2925);
FORCEPROP 1 LAST VOLTAGE 4V
J 0
(-3225 3125);
DISPLAY 0.617021 (-3225 3125);
PAINT SKYBLUE (-3225 3125);
FORCEPROP 1 LAST MATERIAL X6S
J 0
(-3225 3025);
DISPLAY 0.617021 (-3225 3025);
PAINT SKYBLUE (-3225 3025);
FORCEPROP 1 LASTPIN (-3275 3025) $PN 2
J 0
(-3265 3005);
DISPLAY 0.617021 (-3265 3005);
PAINT GREEN (-3265 3005);
FORCEPROP 1 LASTPIN (-3275 3225) $PN 1
J 0
(-3265 3205);
DISPLAY 0.617021 (-3265 3205);
PAINT GREEN (-3265 3205);
FORCEPROP 2 LAST CDS_LIB mstr_discrete
J 0
(-3275 3125);
PAINT ORANGE (-3275 3125);
DISPLAY INVISIBLE (-3275 3125);
FORCEPROP 2 LAST BOM_COST PROC_SOCKET
J 0
(-3225 3325);
DISPLAY 1.021277 (-3225 3325);
PAINT ORANGE (-3225 3325);
DISPLAY INVISIBLE (-3225 3325);
FORCEPROP 2 LAST CDS_SEC 1
J 0
(-3225 3325);
PAINT MONO (-3225 3325);
DISPLAY INVISIBLE (-3225 3325);
FORCEPROP 2 LAST $SEC 1
J 0
(-3225 3325);
PAINT MONO (-3225 3325);
DISPLAY INVISIBLE (-3225 3325);
FORCEPROP 2 LAST CDS_LOCATION C5D11
J 0
(-3225 3225);
DISPLAY 0.617021 (-3225 3225);
PAINT AQUA (-3225 3225);
DISPLAY INVISIBLE (-3225 3225);
FORCEPROP 1 LAST PATH I93
J 0
(-3225 3275);
DISPLAY 0.978723 (-3225 3275);
PAINT WHITE (-3225 3275);
DISPLAY INVISIBLE (-3225 3275);
FORCEPROP 2 LAST ROOM PVCCIN_CPU0_DECAP_VR
J 0
(-3225 3275);
DISPLAY 1.021277 (-3225 3275);
PAINT ORANGE (-3225 3275);
DISPLAY INVISIBLE (-3225 3275);
FORCEADD CAP..1
(-3675 3150);
FORCEPROP 1 LAST LOCATION C5D12
J 0
(-3625 3250);
DISPLAY 0.617021 (-3625 3250);
PAINT AQUA (-3625 3250);
FORCEPROP 1 LAST PART_NUMBER E15431-001
J 0
(-3625 3000);
DISPLAY 0.617021 (-3625 3000);
PAINT BLUE (-3625 3000);
FORCEPROP 1 LAST VALUE 10UF
J 0
(-3625 3200);
DISPLAY 0.617021 (-3625 3200);
PAINT SKYBLUE (-3625 3200);
FORCEPROP 1 LAST TOLERANCE 20%
J 0
(-3625 3100);
DISPLAY 0.617021 (-3625 3100);
PAINT SKYBLUE (-3625 3100);
FORCEPROP 1 LAST PACK_TYPE 0603LF
J 0
(-3625 2950);
DISPLAY 0.617021 (-3625 2950);
PAINT SKYBLUE (-3625 2950);
FORCEPROP 1 LAST VOLTAGE 4V
J 0
(-3625 3150);
DISPLAY 0.617021 (-3625 3150);
PAINT SKYBLUE (-3625 3150);
FORCEPROP 1 LAST MATERIAL X6S
J 0
(-3625 3050);
DISPLAY 0.617021 (-3625 3050);
PAINT SKYBLUE (-3625 3050);
FORCEPROP 1 LASTPIN (-3675 3050) $PN 2
J 0
(-3665 3030);
DISPLAY 0.617021 (-3665 3030);
PAINT GREEN (-3665 3030);
FORCEPROP 1 LASTPIN (-3675 3250) $PN 1
J 0
(-3665 3230);
DISPLAY 0.617021 (-3665 3230);
PAINT GREEN (-3665 3230);
FORCEPROP 2 LAST CDS_LIB mstr_discrete
J 0
(-3675 3150);
PAINT ORANGE (-3675 3150);
DISPLAY INVISIBLE (-3675 3150);
FORCEPROP 2 LAST BOM_COST PROC_SOCKET
J 0
(-3625 3350);
DISPLAY 1.021277 (-3625 3350);
PAINT ORANGE (-3625 3350);
DISPLAY INVISIBLE (-3625 3350);
FORCEPROP 2 LAST CDS_SEC 1
J 0
(-3625 3350);
PAINT MONO (-3625 3350);
DISPLAY INVISIBLE (-3625 3350);
FORCEPROP 2 LAST $SEC 1
J 0
(-3625 3350);
PAINT MONO (-3625 3350);
DISPLAY INVISIBLE (-3625 3350);
FORCEPROP 2 LAST CDS_LOCATION C5D12
J 0
(-3625 3250);
DISPLAY 0.617021 (-3625 3250);
PAINT AQUA (-3625 3250);
DISPLAY INVISIBLE (-3625 3250);
FORCEPROP 1 LAST PATH I94
J 0
(-3625 3300);
DISPLAY 0.978723 (-3625 3300);
PAINT WHITE (-3625 3300);
DISPLAY INVISIBLE (-3625 3300);
FORCEPROP 2 LAST ROOM PVCCIN_CPU0_DECAP_VR
J 0
(-3625 3300);
DISPLAY 1.021277 (-3625 3300);
PAINT ORANGE (-3625 3300);
DISPLAY INVISIBLE (-3625 3300);
FORCEADD CAP_A..1
(-3875 4475);
FORCEPROP 1 LAST LOCATION C5D23
J 0
(-3825 4575);
DISPLAY 0.617021 (-3825 4575);
PAINT AQUA (-3825 4575);
FORCEPROP 1 LAST PART_NUMBER E15431-004
J 0
(-3825 4325);
DISPLAY 0.617021 (-3825 4325);
PAINT BLUE (-3825 4325);
FORCEPROP 1 LAST VALUE 22.0UF
J 0
(-3825 4525);
DISPLAY 0.617021 (-3825 4525);
PAINT SKYBLUE (-3825 4525);
FORCEPROP 1 LAST TOLERANCE 20%
J 0
(-3825 4425);
DISPLAY 0.617021 (-3825 4425);
PAINT SKYBLUE (-3825 4425);
FORCEPROP 1 LAST PACK_TYPE 0603V
J 0
(-3825 4275);
DISPLAY 0.617021 (-3825 4275);
PAINT SKYBLUE (-3825 4275);
FORCEPROP 1 LAST VOLTAGE 4V
J 0
(-3825 4475);
DISPLAY 0.617021 (-3825 4475);
PAINT SKYBLUE (-3825 4475);
FORCEPROP 1 LAST MATERIAL X6S
J 0
(-3825 4375);
DISPLAY 0.617021 (-3825 4375);
PAINT SKYBLUE (-3825 4375);
FORCEPROP 1 LASTPIN (-3875 4575) $PN 1
J 0
(-3865 4555);
DISPLAY 0.617021 (-3865 4555);
PAINT GREEN (-3865 4555);
FORCEPROP 1 LASTPIN (-3875 4375) $PN 2
J 0
(-3865 4355);
DISPLAY 0.617021 (-3865 4355);
PAINT GREEN (-3865 4355);
FORCEPROP 2 LAST CDS_LOCATION C5D23
J 0
(-3825 4575);
DISPLAY 0.617021 (-3825 4575);
PAINT AQUA (-3825 4575);
DISPLAY INVISIBLE (-3825 4575);
FORCEPROP 2 LAST BOM_COST PROC_SOCKET
J 0
(-3825 4675);
DISPLAY 1.021277 (-3825 4675);
PAINT ORANGE (-3825 4675);
DISPLAY INVISIBLE (-3825 4675);
FORCEPROP 2 LAST CDS_LIB dev_discrete
J 0
(-3875 4475);
PAINT ORANGE (-3875 4475);
DISPLAY INVISIBLE (-3875 4475);
FORCEPROP 2 LAST CDS_SEC 1
J 0
(-3825 4675);
PAINT MONO (-3825 4675);
DISPLAY INVISIBLE (-3825 4675);
FORCEPROP 2 LAST $SEC 1
J 0
(-3825 4675);
PAINT MONO (-3825 4675);
DISPLAY INVISIBLE (-3825 4675);
FORCEPROP 1 LAST PATH I98
J 0
(-3825 4625);
DISPLAY 0.978723 (-3825 4625);
PAINT WHITE (-3825 4625);
DISPLAY INVISIBLE (-3825 4625);
FORCEPROP 2 LAST ROOM PVCCIN_CPU0_DECAP_VR
J 0
(-3825 4625);
DISPLAY 1.021277 (-3825 4625);
PAINT ORANGE (-3825 4625);
DISPLAY INVISIBLE (-3825 4625);
FORCEADD PVSA_CPU0..1
(-4075 3400);
FORCEPROP 3 LASTPIN (-4075 3350) SIG_NAME PVSA_CPU0\g
J 0
(-4065 3360);
DISPLAY 0.659574 (-4065 3360);
PAINT MONO (-4065 3360);
DISPLAY INVISIBLE (-4065 3360);
FORCEPROP 1 LAST VOLTAGE 1.1V
J 0
(-4120 3357);
DISPLAY 0.340426 (-4120 3357);
PAINT SKYBLUE (-4120 3357);
DISPLAY INVISIBLE (-4120 3357);
FORCEPROP 2 LAST CDS_LIB mstr_symbols
J 0
(-4075 3400);
PAINT ORANGE (-4075 3400);
DISPLAY INVISIBLE (-4075 3400);
FORCEPROP 1 LAST BODY_TYPE PLUMBING
J 0
(-4120 3357);
DISPLAY 0.340426 (-4120 3357);
PAINT GREEN (-4120 3357);
DISPLAY INVISIBLE (-4120 3357);
FORCEPROP 1 LAST PATH I99
J 0
(-4025 3425);
DISPLAY 0.872340 (-4025 3425);
PAINT AQUA (-4025 3425);
DISPLAY INVISIBLE (-4025 3425);
FORCEPROP 1 LAST HDL_POWER PVSA_CPU0
J 1
(-4075 3450);
DISPLAY 0.872340 (-4075 3450);
PAINT GREEN (-4075 3450);
DISPLAY INVISIBLE (-4075 3450);
FORCEADD DESIGN_NOTE..1
(-1750 3275);
PAINT PURPLE (-1750 3275);
FORCEPROP 0 LAST L1 * HIGH TEMPERATURE
J 0
(-1950 3150);
PAINT VIOLET (-1950 3150);
FORCEPROP 0 LAST L2 CAPACITORS.
J 0
(-1950 3100);
PAINT VIOLET (-1950 3100);
FORCEPROP 0 LAST L3 * TO BE PLACED IN
J 0
(-1950 3025);
PAINT VIOLET (-1950 3025);
FORCEPROP 0 LAST L4 SKT 0 CAVITY (TOP,48.11MIL/1.22MM)
J 0
(-1950 2975);
PAINT VIOLET (-1950 2975);
FORCEPROP 2 LAST CDS_LIB mstr_symbols
J 0
(-1750 3275);
PAINT MONO (-1750 3275);
DISPLAY INVISIBLE (-1750 3275);
FORCEPROP 1 LAST COMMENT_BODY TRUE
J 0
(-1725 3375);
DISPLAY 1.319149 (-1725 3375);
PAINT GREEN (-1725 3375);
DISPLAY INVISIBLE (-1725 3375);
FORCEADD DESIGN_NOTE..1
(-1250 1025);
PAINT PURPLE (-1250 1025);
FORCEPROP 0 LAST L3 * TO BE PLACED IN
J 0
(-1450 775);
PAINT VIOLET (-1450 775);
FORCEPROP 0 LAST L4 SKT 0 CAVITY (BOTTOM, 98MIL/2.49MM)
J 0
(-1450 725);
PAINT VIOLET (-1450 725);
FORCEPROP 0 LAST L2 CAPACITORS.
J 0
(-1450 850);
PAINT VIOLET (-1450 850);
FORCEPROP 0 LAST L1 * HIGH TEMPERATURE
J 0
(-1450 900);
PAINT VIOLET (-1450 900);
FORCEPROP 1 LAST COMMENT_BODY TRUE
J 0
(-1225 1125);
DISPLAY 1.319149 (-1225 1125);
PAINT GREEN (-1225 1125);
DISPLAY INVISIBLE (-1225 1125);
FORCEPROP 2 LAST CDS_LIB mstr_symbols
J 0
(-1250 1025);
PAINT MONO (-1250 1025);
DISPLAY INVISIBLE (-1250 1025);
FORCEADD INTEL_CORP_BPAGE..1
(0 0);
FORCEPROP 1 LAST CDS_CON_LAST_MODIFIED Tue Dec 01 11:51:25 2015
J 0
(-1425 325);
PAINT ORANGE (-1425 325);
DISPLAY INVISIBLE (-1425 325);
FORCEPROP 1 LAST CUSTOM_TXT_CDS <CURRENT_DESIGN_SHEET> OF <TOTAL_DESIGN_SHEETS>
J 0
(-500 25);
PAINT GREEN (-500 25);
FORCEPROP 1 LAST CUSTOM_TXT_CDS <CON_LAST_MODIFIED>
J 0
(-1925 350);
PAINT GREEN (-1925 350);
FORCEPROP 2 LAST CUSTOM_TXT_CDS <XR_PAGE_TITLE>
J 0
(-7890 5250);
DISPLAY 0.638298 (-7890 5250);
PAINT PINK (-7890 5250);
DISPLAY INVISIBLE (-7890 5250);
FORCEPROP 1 LAST SCH_ADDRESS3 Santa Clara, CA 95052-8119
J 0
(-3975 25);
DISPLAY 0.617021 (-3975 25);
PAINT GREEN (-3975 25);
FORCEPROP 1 LAST SCH_ADDRESS2 P.O. BOX 58119
J 0
(-3975 75);
DISPLAY 0.617021 (-3975 75);
PAINT GREEN (-3975 75);
FORCEPROP 1 LAST SCH_ADDRESS1 2200 Mission College Blvd.
J 0
(-3975 125);
DISPLAY 0.617021 (-3975 125);
PAINT GREEN (-3975 125);
FORCEPROP 1 LAST SCH_TITLE CPU0 DECOUPLING CAVITY CAPS
J 0
(-7950 50);
DISPLAY 1.212766 (-7950 50);
PAINT ORANGE (-7950 50);
FORCEPROP 1 LAST SCH_REV 2.420
J 0
(-250 150);
DISPLAY 0.978723 (-250 150);
PAINT YELLOW (-250 150);
FORCEPROP 1 LAST SCH_DEPT BESD
J 1
(-4450 100);
DISPLAY 1.212766 (-4450 100);
PAINT YELLOW (-4450 100);
FORCEPROP 1 LAST SCH_NUMBER H4694802
J 0
(-1300 150);
DISPLAY 1.212766 (-1300 150);
PAINT YELLOW (-1300 150);
FORCEPROP 2 LAST CDS_LIB mstr_symbols
J 0
(0 0);
PAINT MONO (0 0);
DISPLAY INVISIBLE (0 0);
FORCEPROP 2 LAST PAGE_BORDER TRUE
J 0
(-7890 5250);
DISPLAY 0.638298 (-7890 5250);
PAINT PINK (-7890 5250);
DISPLAY INVISIBLE (-7890 5250);
FORCEPROP 1 LAST COMMENT_BODY TRUE
J 0
(12 12);
DISPLAY 0.468085 (12 12);
PAINT GREEN (12 12);
DISPLAY INVISIBLE (12 12);
FORCEPROP 2 LAST CDS_XR_PAGE_TITLE CR-42 : @BASEBOARD_FAB2_LIB.BASEBOARD_FAB2(SCH_1):PAGE42
J 0
(-7890 5250);
DISPLAY 0.638298 (-7890 5250);
PAINT PINK (-7890 5250);
DISPLAY INVISIBLE (-7890 5250);
WIRE 16 -1 (-5925 3700)(-5925 3600);
WIRE 16 -1 (-5925 3600)(-5625 3600);
WIRE 16 -1 (-5625 3700)(-5625 3600);
WIRE 16 -1 (-5325 3600)(-5625 3600);
WIRE 16 -1 (-5325 3700)(-5325 3600);
WIRE 16 -1 (-5000 3600)(-5325 3600);
WIRE 16 -1 (-5000 3675)(-5000 3600);
WIRE 16 -1 (-4700 3600)(-5000 3600);
WIRE 16 -1 (-4700 3675)(-4700 3600);
WIRE 16 -1 (-4425 3600)(-4700 3600);
WIRE 16 -1 (-4425 3700)(-4425 3600);
WIRE 16 -1 (-4425 3525)(-4425 3600);
WIRE 16 -1 (-5950 4375)(-5950 4275);
WIRE 16 -1 (-5950 4275)(-5625 4275);
WIRE 16 -1 (-5625 4375)(-5625 4275);
WIRE 16 -1 (-5325 4275)(-5625 4275);
WIRE 16 -1 (-5325 4375)(-5325 4275);
WIRE 16 -1 (-5000 4275)(-5325 4275);
WIRE 16 -1 (-5000 4375)(-5000 4275);
WIRE 16 -1 (-4700 4275)(-5000 4275);
WIRE 16 -1 (-4700 4350)(-4700 4275);
WIRE 16 -1 (-4700 4275)(-4450 4275);
WIRE 16 -1 (-4450 4375)(-4450 4275);
WIRE 16 -1 (-4450 4200)(-4450 4275);
WIRE 16 -1 (-5900 3050)(-5900 2975);
WIRE 16 -1 (-5900 2975)(-5625 2975);
WIRE 16 -1 (-5625 3075)(-5625 2975);
WIRE 16 -1 (-5350 2975)(-5625 2975);
WIRE 16 -1 (-5350 3050)(-5350 2975);
WIRE 16 -1 (-5075 2975)(-5350 2975);
WIRE 16 -1 (-5075 3050)(-5075 2975);
WIRE 16 -1 (-4750 2975)(-5075 2975);
WIRE 16 -1 (-4750 3075)(-4750 2975);
WIRE 16 -1 (-4750 2975)(-4450 2975);
WIRE 16 -1 (-4450 3100)(-4450 2975);
WIRE 16 -1 (-4450 2900)(-4450 2975);
WIRE 16 -1 (-4450 4650)(-4450 4575);
WIRE 16 -1 (-4700 4650)(-4450 4650);
WIRE 16 -1 (-4700 4650)(-5000 4650);
WIRE 16 -1 (-4700 4650)(-4700 4550);
WIRE 16 -1 (-5000 4575)(-5000 4650);
WIRE 16 -1 (-5000 4650)(-5325 4650);
WIRE 16 -1 (-5325 4575)(-5325 4650);
WIRE 16 -1 (-5325 4650)(-5625 4650);
WIRE 16 -1 (-5625 4575)(-5625 4650);
WIRE 16 -1 (-5625 4650)(-5950 4650);
WIRE 16 -1 (-5950 4650)(-5950 4700);
WIRE 16 -1 (-5950 4650)(-5950 4575);
WIRE 16 -1 (-4425 3975)(-4425 3900);
WIRE 16 -1 (-4700 3975)(-4425 3975);
WIRE 16 -1 (-4700 3975)(-4700 3875);
WIRE 16 -1 (-4700 3975)(-5000 3975);
WIRE 16 -1 (-5000 3875)(-5000 3975);
WIRE 16 -1 (-5000 3975)(-5325 3975);
WIRE 16 -1 (-5325 3900)(-5325 3975);
WIRE 16 -1 (-5325 3975)(-5625 3975);
WIRE 16 -1 (-5625 3900)(-5625 3975);
WIRE 16 -1 (-5625 3975)(-5925 3975);
WIRE 16 -1 (-5925 3975)(-5925 4025);
WIRE 16 -1 (-5925 3975)(-5925 3900);
WIRE 16 -1 (-4450 3350)(-4450 3300);
WIRE 16 -1 (-4750 3350)(-4450 3350);
WIRE 16 -1 (-4750 3350)(-4750 3275);
WIRE 16 -1 (-4750 3350)(-5075 3350);
WIRE 16 -1 (-5075 3250)(-5075 3350);
WIRE 16 -1 (-5075 3350)(-5350 3350);
WIRE 16 -1 (-5350 3250)(-5350 3350);
WIRE 16 -1 (-5350 3350)(-5625 3350);
WIRE 16 -1 (-5625 3275)(-5625 3350);
WIRE 16 -1 (-5625 3350)(-5900 3350);
WIRE 16 -1 (-5900 3350)(-5900 3400);
WIRE 16 -1 (-5900 3350)(-5900 3250);
WIRE 16 -1 (-7725 4375)(-7725 4275);
WIRE 16 -1 (-7725 4275)(-7375 4275);
WIRE 16 -1 (-7375 4375)(-7375 4275);
WIRE 16 -1 (-7375 4275)(-7050 4275);
WIRE 16 -1 (-7050 4375)(-7050 4275);
WIRE 16 -1 (-7050 4275)(-6675 4275);
WIRE 16 -1 (-6675 4375)(-6675 4275);
WIRE 16 -1 (-6675 4275)(-6350 4275);
WIRE 16 -1 (-6350 4375)(-6350 4275);
WIRE 16 -1 (-6350 4200)(-6350 4275);
WIRE 16 -1 (-7675 3700)(-7675 3600);
WIRE 16 -1 (-7675 3600)(-7325 3600);
WIRE 16 -1 (-7325 3700)(-7325 3600);
WIRE 16 -1 (-7325 3600)(-7000 3600);
WIRE 16 -1 (-7000 3700)(-7000 3600);
WIRE 16 -1 (-7000 3600)(-6650 3600);
WIRE 16 -1 (-6650 3700)(-6650 3600);
WIRE 16 -1 (-6650 3600)(-6300 3600);
WIRE 16 -1 (-6300 3700)(-6300 3600);
WIRE 16 -1 (-6300 3525)(-6300 3600);
WIRE 16 -1 (-7625 3075)(-7625 2975);
WIRE 16 -1 (-7625 2975)(-7275 2975);
WIRE 16 -1 (-7275 3075)(-7275 2975);
WIRE 16 -1 (-7275 2975)(-6950 2975);
WIRE 16 -1 (-6950 3075)(-6950 2975);
WIRE 16 -1 (-6950 2975)(-6600 2975);
WIRE 16 -1 (-6600 3050)(-6600 2975);
WIRE 16 -1 (-6600 2975)(-6250 2975);
WIRE 16 -1 (-6250 3075)(-6250 2975);
WIRE 16 -1 (-6250 2900)(-6250 2975);
WIRE 16 -1 (-6350 4650)(-6350 4575);
WIRE 16 -1 (-6350 4650)(-6675 4650);
WIRE 16 -1 (-6675 4575)(-6675 4650);
WIRE 16 -1 (-7050 4650)(-6675 4650);
WIRE 16 -1 (-7050 4575)(-7050 4650);
WIRE 16 -1 (-7375 4650)(-7050 4650);
WIRE 16 -1 (-7375 4575)(-7375 4650);
WIRE 16 -1 (-7725 4650)(-7375 4650);
WIRE 16 -1 (-7725 4650)(-7725 4700);
WIRE 16 -1 (-7725 4650)(-7725 4575);
WIRE 16 -1 (-6300 3975)(-6300 3900);
WIRE 16 -1 (-6300 3975)(-6650 3975);
WIRE 16 -1 (-6650 3900)(-6650 3975);
WIRE 16 -1 (-7000 3975)(-6650 3975);
WIRE 16 -1 (-7000 3900)(-7000 3975);
WIRE 16 -1 (-7325 3975)(-7000 3975);
WIRE 16 -1 (-7325 3900)(-7325 3975);
WIRE 16 -1 (-7675 3975)(-7325 3975);
WIRE 16 -1 (-7675 3975)(-7675 4025);
WIRE 16 -1 (-7675 3975)(-7675 3900);
WIRE 16 -1 (-6250 3350)(-6250 3275);
WIRE 16 -1 (-6250 3350)(-6600 3350);
WIRE 16 -1 (-6600 3250)(-6600 3350);
WIRE 16 -1 (-6950 3350)(-6600 3350);
WIRE 16 -1 (-6950 3275)(-6950 3350);
WIRE 16 -1 (-7275 3350)(-6950 3350);
WIRE 16 -1 (-7275 3275)(-7275 3350);
WIRE 16 -1 (-7625 3350)(-7275 3350);
WIRE 16 -1 (-7625 3350)(-7625 3400);
WIRE 16 -1 (-7625 3350)(-7625 3275);
WIRE 16 -1 (-525 4650)(-800 4650);
WIRE 16 -1 (-525 4650)(-525 4575);
WIRE 16 -1 (-800 4650)(-800 4550);
WIRE 16 -1 (-800 4650)(-1100 4650);
WIRE 16 -1 (-1100 4550)(-1100 4650);
WIRE 16 -1 (-1100 4650)(-1400 4650);
WIRE 16 -1 (-1400 4575)(-1400 4650);
WIRE 16 -1 (-1400 4650)(-1700 4650);
WIRE 16 -1 (-1700 4550)(-1700 4650);
WIRE 16 -1 (-1700 4650)(-2000 4650);
WIRE 16 -1 (-2000 4650)(-2000 4575);
WIRE 16 -1 (-2000 4650)(-2275 4650);
WIRE 16 -1 (-2275 4650)(-2275 4550);
WIRE 16 -1 (-2275 4650)(-2575 4650);
WIRE 16 -1 (-2575 4650)(-2825 4650);
WIRE 16 -1 (-2575 4650)(-2575 4575);
WIRE 16 -1 (-2825 4650)(-2825 4575);
WIRE 16 -1 (-2825 4650)(-3075 4650);
WIRE 16 -1 (-3075 4550)(-3075 4650);
WIRE 16 -1 (-3075 4650)(-3350 4650);
WIRE 16 -1 (-3350 4575)(-3350 4650);
WIRE 16 -1 (-3350 4650)(-3625 4650);
WIRE 16 -1 (-3625 4575)(-3625 4650);
WIRE 16 -1 (-3625 4650)(-3875 4650);
WIRE 16 -1 (-3875 4650)(-3875 4700);
WIRE 16 -1 (-3875 4650)(-3875 4575);
WIRE 16 -1 (-375 2350)(-375 2250);
WIRE 16 -1 (-625 2350)(-375 2350);
WIRE 16 -1 (-625 2250)(-625 2350);
WIRE 16 -1 (-875 2350)(-625 2350);
WIRE 16 -1 (-875 2250)(-875 2350);
WIRE 16 -1 (-1125 2350)(-875 2350);
WIRE 16 -1 (-1125 2250)(-1125 2350);
WIRE 16 -1 (-1400 2350)(-1125 2350);
WIRE 16 -1 (-1400 2350)(-1400 2250);
WIRE 16 -1 (-1650 2350)(-1400 2350);
WIRE 16 -1 (-1650 2250)(-1650 2350);
WIRE 16 -1 (-1900 2350)(-1650 2350);
WIRE 16 -1 (-1900 2250)(-1900 2350);
WIRE 16 -1 (-2150 2350)(-1900 2350);
WIRE 16 -1 (-2150 2350)(-2150 2250);
WIRE 16 -1 (-2150 2350)(-2425 2350);
WIRE 16 -1 (-2425 2275)(-2425 2350);
WIRE 16 -1 (-2700 2350)(-2425 2350);
WIRE 16 -1 (-2700 2275)(-2700 2350);
WIRE 16 -1 (-2700 2350)(-3000 2350);
WIRE 16 -1 (-3000 2275)(-3000 2350);
WIRE 16 -1 (-3000 2350)(-3275 2350);
WIRE 16 -1 (-3275 2350)(-3275 2275);
WIRE 16 -1 (-3275 2350)(-3550 2350);
WIRE 16 -1 (-3550 2350)(-3550 2275);
WIRE 16 -1 (-3550 2350)(-3825 2350);
WIRE 16 -1 (-3825 2275)(-3825 2350);
WIRE 16 -1 (-3825 2350)(-4100 2350);
WIRE 16 -1 (-4100 2275)(-4100 2350);
WIRE 16 -1 (-4100 2350)(-4425 2350);
WIRE 16 -1 (-4425 2275)(-4425 2350);
WIRE 16 -1 (-4425 2350)(-4675 2350);
WIRE 16 -1 (-4675 2350)(-4675 2475);
WIRE 16 -1 (-4675 2350)(-4675 2275);
WIRE 16 -1 (-1950 1125)(-1950 1050);
WIRE 16 -1 (-2250 1125)(-1950 1125);
WIRE 16 -1 (-2250 1050)(-2250 1125);
WIRE 16 -1 (-2250 1125)(-2550 1125);
WIRE 16 -1 (-2550 1050)(-2550 1125);
WIRE 16 -1 (-2850 1125)(-2550 1125);
WIRE 16 -1 (-2850 1050)(-2850 1125);
WIRE 16 -1 (-2850 1125)(-3175 1125);
WIRE 16 -1 (-3175 1125)(-3175 1200);
WIRE 16 -1 (-3175 1125)(-3175 1050);
WIRE 16 -1 (-600 4050)(-600 3900);
WIRE 16 -1 (-600 4050)(-975 4050);
WIRE 16 -1 (-975 4050)(-975 3925);
WIRE 16 -1 (-1375 4050)(-975 4050);
WIRE 16 -1 (-1375 4050)(-1375 3950);
WIRE 16 -1 (-1700 4050)(-1375 4050);
WIRE 16 -1 (-1700 4050)(-1700 3950);
WIRE 16 -1 (-2150 4050)(-1700 4050);
WIRE 16 -1 (-2150 4050)(-2150 3950);
WIRE 16 -1 (-2525 4050)(-2150 4050);
WIRE 16 -1 (-2525 4075)(-2525 4050);
WIRE 16 -1 (-2525 4050)(-2525 3925);
WIRE 16 -1 (-2525 3725)(-2525 3600);
WIRE 16 -1 (-2525 3600)(-2150 3600);
WIRE 16 -1 (-2150 3750)(-2150 3600);
WIRE 16 -1 (-2150 3600)(-1700 3600);
WIRE 16 -1 (-1700 3750)(-1700 3600);
WIRE 16 -1 (-1700 3600)(-1375 3600);
WIRE 16 -1 (-1375 3750)(-1375 3600);
WIRE 16 -1 (-1375 3600)(-975 3600);
WIRE 16 -1 (-975 3725)(-975 3600);
WIRE 16 -1 (-975 3600)(-600 3600);
WIRE 16 -1 (-600 3700)(-600 3600);
WIRE 16 -1 (-600 3600)(-600 3525);
WIRE 16 -1 (-3175 850)(-3175 750);
WIRE 16 -1 (-3175 750)(-2850 750);
WIRE 16 -1 (-2850 850)(-2850 750);
WIRE 16 -1 (-2850 750)(-2550 750);
WIRE 16 -1 (-2550 850)(-2550 750);
WIRE 16 -1 (-2250 750)(-2550 750);
WIRE 16 -1 (-2250 850)(-2250 750);
WIRE 16 -1 (-1950 750)(-2250 750);
WIRE 16 -1 (-1950 850)(-1950 750);
WIRE 16 -1 (-1950 675)(-1950 750);
WIRE 16 -1 (-4275 875)(-4275 775);
WIRE 16 -1 (-4275 775)(-3925 775);
WIRE 16 -1 (-3925 875)(-3925 775);
WIRE 16 -1 (-3925 775)(-3600 775);
WIRE 16 -1 (-3600 875)(-3600 775);
WIRE 16 -1 (-3600 700)(-3600 775);
WIRE 16 -1 (-3600 1075)(-3600 1150);
WIRE 16 -1 (-3925 1150)(-3600 1150);
WIRE 16 -1 (-3925 1075)(-3925 1150);
WIRE 16 -1 (-4275 1150)(-3925 1150);
WIRE 16 -1 (-4275 1150)(-4275 1200);
WIRE 16 -1 (-4275 1150)(-4275 1075);
WIRE 16 -1 (-5975 2125)(-5975 2025);
WIRE 16 -1 (-5975 2025)(-5675 2025);
WIRE 16 -1 (-5675 2125)(-5675 2025);
WIRE 16 -1 (-5350 2025)(-5675 2025);
WIRE 16 -1 (-5350 2125)(-5350 2025);
WIRE 16 -1 (-5100 2025)(-5350 2025);
WIRE 16 -1 (-5100 2100)(-5100 2025);
WIRE 16 -1 (-5100 1925)(-5100 2025);
WIRE 16 -1 (-5975 1475)(-5975 1375);
WIRE 16 -1 (-5975 1375)(-5625 1375);
WIRE 16 -1 (-5625 1475)(-5625 1375);
WIRE 16 -1 (-5625 1375)(-5300 1375);
WIRE 16 -1 (-5300 1475)(-5300 1375);
WIRE 16 -1 (-5300 1275)(-5300 1375);
WIRE 16 -1 (-5950 800)(-5950 700);
WIRE 16 -1 (-5950 700)(-5600 700);
WIRE 16 -1 (-5600 800)(-5600 700);
WIRE 16 -1 (-5600 700)(-5275 700);
WIRE 16 -1 (-5275 800)(-5275 700);
WIRE 16 -1 (-5275 650)(-5275 700);
WIRE 16 -1 (-5100 2300)(-5100 2400);
WIRE 16 -1 (-5100 2400)(-5350 2400);
WIRE 16 -1 (-5350 2325)(-5350 2400);
WIRE 16 -1 (-5350 2400)(-5675 2400);
WIRE 16 -1 (-5675 2325)(-5675 2400);
WIRE 16 -1 (-5975 2400)(-5675 2400);
WIRE 16 -1 (-5975 2400)(-5975 2450);
WIRE 16 -1 (-5975 2400)(-5975 2325);
WIRE 16 -1 (-5300 1675)(-5300 1750);
WIRE 16 -1 (-5625 1750)(-5300 1750);
WIRE 16 -1 (-5625 1675)(-5625 1750);
WIRE 16 -1 (-5975 1750)(-5625 1750);
WIRE 16 -1 (-5975 1750)(-5975 1800);
WIRE 16 -1 (-5975 1750)(-5975 1675);
WIRE 16 -1 (-5275 1000)(-5275 1075);
WIRE 16 -1 (-5600 1075)(-5275 1075);
WIRE 16 -1 (-5600 1000)(-5600 1075);
WIRE 16 -1 (-5950 1075)(-5600 1075);
WIRE 16 -1 (-5950 1075)(-5950 1125);
WIRE 16 -1 (-5950 1075)(-5950 1000);
WIRE 16 -1 (-7725 2125)(-7725 2025);
WIRE 16 -1 (-7725 2025)(-7375 2025);
WIRE 16 -1 (-7375 2125)(-7375 2025);
WIRE 16 -1 (-7375 2025)(-7050 2025);
WIRE 16 -1 (-7050 2125)(-7050 2025);
WIRE 16 -1 (-7050 2025)(-6700 2025);
WIRE 16 -1 (-6700 2125)(-6700 2025);
WIRE 16 -1 (-6700 2025)(-6350 2025);
WIRE 16 -1 (-6350 2125)(-6350 2025);
WIRE 16 -1 (-6350 1950)(-6350 2025);
WIRE 16 -1 (-7725 1475)(-7725 1375);
WIRE 16 -1 (-7725 1375)(-7375 1375);
WIRE 16 -1 (-7375 1475)(-7375 1375);
WIRE 16 -1 (-7375 1375)(-7050 1375);
WIRE 16 -1 (-7050 1475)(-7050 1375);
WIRE 16 -1 (-7050 1375)(-6700 1375);
WIRE 16 -1 (-6700 1475)(-6700 1375);
WIRE 16 -1 (-6700 1375)(-6350 1375);
WIRE 16 -1 (-6350 1475)(-6350 1375);
WIRE 16 -1 (-6350 1300)(-6350 1375);
WIRE 16 -1 (-4675 2075)(-4675 1975);
WIRE 16 -1 (-4675 1975)(-4425 1975);
WIRE 16 -1 (-4425 2075)(-4425 1975);
WIRE 16 -1 (-4100 1975)(-4425 1975);
WIRE 16 -1 (-4100 2075)(-4100 1975);
WIRE 16 -1 (-3825 1975)(-4100 1975);
WIRE 16 -1 (-3825 2075)(-3825 1975);
WIRE 16 -1 (-3550 1975)(-3825 1975);
WIRE 16 -1 (-3550 2075)(-3550 1975);
WIRE 16 -1 (-3275 1975)(-3550 1975);
WIRE 16 -1 (-3275 2075)(-3275 1975);
WIRE 16 -1 (-3275 1975)(-3000 1975);
WIRE 16 -1 (-3000 2075)(-3000 1975);
WIRE 16 -1 (-2700 1975)(-3000 1975);
WIRE 16 -1 (-2700 2075)(-2700 1975);
WIRE 16 -1 (-2425 1975)(-2700 1975);
WIRE 16 -1 (-2425 2075)(-2425 1975);
WIRE 16 -1 (-2150 1975)(-2425 1975);
WIRE 16 -1 (-2150 2050)(-2150 1975);
WIRE 16 -1 (-1900 1975)(-2150 1975);
WIRE 16 -1 (-1900 2050)(-1900 1975);
WIRE 16 -1 (-1650 1975)(-1900 1975);
WIRE 16 -1 (-1650 2050)(-1650 1975);
WIRE 16 -1 (-1400 1975)(-1650 1975);
WIRE 16 -1 (-1400 2050)(-1400 1975);
WIRE 16 -1 (-1125 1975)(-1400 1975);
WIRE 16 -1 (-1125 2050)(-1125 1975);
WIRE 16 -1 (-875 1975)(-1125 1975);
WIRE 16 -1 (-875 2050)(-875 1975);
WIRE 16 -1 (-625 1975)(-875 1975);
WIRE 16 -1 (-625 2050)(-625 1975);
WIRE 16 -1 (-375 1975)(-625 1975);
WIRE 16 -1 (-375 2050)(-375 1975);
WIRE 16 -1 (-375 1825)(-375 1975);
WIRE 16 -1 (-7725 825)(-7725 725);
WIRE 16 -1 (-7725 725)(-7375 725);
WIRE 16 -1 (-7375 825)(-7375 725);
WIRE 16 -1 (-7375 725)(-7050 725);
WIRE 16 -1 (-7050 825)(-7050 725);
WIRE 16 -1 (-7050 725)(-6700 725);
WIRE 16 -1 (-6700 825)(-6700 725);
WIRE 16 -1 (-6700 725)(-6350 725);
WIRE 16 -1 (-6350 825)(-6350 725);
WIRE 16 -1 (-6350 650)(-6350 725);
WIRE 16 -1 (-6350 2400)(-6350 2325);
WIRE 16 -1 (-6350 2400)(-6700 2400);
WIRE 16 -1 (-6700 2325)(-6700 2400);
WIRE 16 -1 (-7050 2400)(-6700 2400);
WIRE 16 -1 (-7050 2325)(-7050 2400);
WIRE 16 -1 (-7375 2400)(-7050 2400);
WIRE 16 -1 (-7375 2325)(-7375 2400);
WIRE 16 -1 (-7725 2400)(-7375 2400);
WIRE 16 -1 (-7725 2400)(-7725 2450);
WIRE 16 -1 (-7725 2400)(-7725 2325);
WIRE 16 -1 (-6350 1750)(-6350 1675);
WIRE 16 -1 (-6350 1750)(-6700 1750);
WIRE 16 -1 (-6700 1675)(-6700 1750);
WIRE 16 -1 (-7050 1750)(-6700 1750);
WIRE 16 -1 (-7050 1675)(-7050 1750);
WIRE 16 -1 (-7375 1750)(-7050 1750);
WIRE 16 -1 (-7375 1675)(-7375 1750);
WIRE 16 -1 (-7725 1750)(-7375 1750);
WIRE 16 -1 (-7725 1750)(-7725 1800);
WIRE 16 -1 (-7725 1750)(-7725 1675);
WIRE 16 -1 (-6350 1100)(-6350 1025);
WIRE 16 -1 (-6350 1100)(-6700 1100);
WIRE 16 -1 (-6700 1025)(-6700 1100);
WIRE 16 -1 (-7050 1100)(-6700 1100);
WIRE 16 -1 (-7050 1025)(-7050 1100);
WIRE 16 -1 (-7375 1100)(-7050 1100);
WIRE 16 -1 (-7375 1025)(-7375 1100);
WIRE 16 -1 (-7725 1100)(-7375 1100);
WIRE 16 -1 (-7725 1100)(-7725 1025);
WIRE 16 -1 (-7725 1100)(-7725 1150);
WIRE 16 -1 (-3875 4375)(-3875 4275);
WIRE 16 -1 (-3875 4275)(-3625 4275);
WIRE 16 -1 (-3625 4375)(-3625 4275);
WIRE 16 -1 (-3350 4275)(-3625 4275);
WIRE 16 -1 (-3350 4375)(-3350 4275);
WIRE 16 -1 (-3075 4275)(-3350 4275);
WIRE 16 -1 (-3075 4350)(-3075 4275);
WIRE 16 -1 (-2825 4275)(-3075 4275);
WIRE 16 -1 (-2825 4375)(-2825 4275);
WIRE 16 -1 (-2575 4275)(-2825 4275);
WIRE 16 -1 (-2575 4375)(-2575 4275);
WIRE 16 -1 (-2275 4275)(-2575 4275);
WIRE 16 -1 (-2275 4350)(-2275 4275);
WIRE 16 -1 (-2000 4275)(-2275 4275);
WIRE 16 -1 (-2000 4375)(-2000 4275);
WIRE 16 -1 (-1700 4275)(-2000 4275);
WIRE 16 -1 (-1700 4350)(-1700 4275);
WIRE 16 -1 (-1400 4275)(-1700 4275);
WIRE 16 -1 (-1400 4375)(-1400 4275);
WIRE 16 -1 (-1100 4275)(-1400 4275);
WIRE 16 -1 (-1100 4350)(-1100 4275);
WIRE 16 -1 (-800 4275)(-1100 4275);
WIRE 16 -1 (-800 4350)(-800 4275);
WIRE 16 -1 (-525 4275)(-800 4275);
WIRE 16 -1 (-525 4375)(-525 4275);
WIRE 16 -1 (-525 4200)(-525 4275);
WIRE 16 -1 (-4075 3675)(-4075 3600);
WIRE 16 -1 (-4075 3600)(-3825 3600);
WIRE 16 -1 (-3825 3700)(-3825 3600);
WIRE 16 -1 (-3600 3600)(-3825 3600);
WIRE 16 -1 (-3600 3700)(-3600 3600);
WIRE 16 -1 (-3375 3600)(-3600 3600);
WIRE 16 -1 (-3375 3700)(-3375 3600);
WIRE 16 -1 (-3125 3600)(-3375 3600);
WIRE 16 -1 (-3125 3675)(-3125 3600);
WIRE 16 -1 (-2850 3600)(-3125 3600);
WIRE 16 -1 (-2850 3675)(-2850 3600);
WIRE 16 -1 (-2850 3550)(-2850 3600);
WIRE 16 -1 (-2850 3975)(-2850 3875);
WIRE 16 -1 (-2850 3975)(-3125 3975);
WIRE 16 -1 (-3125 3875)(-3125 3975);
WIRE 16 -1 (-3375 3975)(-3125 3975);
WIRE 16 -1 (-3375 3900)(-3375 3975);
WIRE 16 -1 (-3375 3975)(-3600 3975);
WIRE 16 -1 (-3600 3900)(-3600 3975);
WIRE 16 -1 (-3600 3975)(-3825 3975);
WIRE 16 -1 (-3825 3900)(-3825 3975);
WIRE 16 -1 (-3825 3975)(-4075 3975);
WIRE 16 -1 (-4075 3975)(-4075 4025);
WIRE 16 -1 (-4075 3975)(-4075 3875);
WIRE 16 -1 (-4075 3025)(-4075 2925);
WIRE 16 -1 (-4075 2925)(-3675 2925);
WIRE 16 -1 (-3675 3050)(-3675 2925);
WIRE 16 -1 (-3275 2925)(-3675 2925);
WIRE 16 -1 (-3275 3025)(-3275 2925);
WIRE 16 -1 (-2875 2925)(-3275 2925);
WIRE 16 -1 (-2875 2925)(-2875 3025);
WIRE 16 -1 (-2875 2850)(-2875 2925);
WIRE 16 -1 (-2875 3325)(-2875 3225);
WIRE 16 -1 (-2875 3325)(-3275 3325);
WIRE 16 -1 (-3275 3225)(-3275 3325);
WIRE 16 -1 (-3275 3325)(-3675 3325);
WIRE 16 -1 (-3675 3250)(-3675 3325);
WIRE 16 -1 (-4075 3325)(-3675 3325);
WIRE 16 -1 (-4075 3225)(-4075 3325);
WIRE 16 -1 (-4075 3325)(-4075 3350);
WIRE 16 2175 (-7900 4875)(-125 4875);
WIRE 16 2175 (-7900 2700)(-7900 4875);
WIRE 16 2175 (-125 4875)(-125 2700);
WIRE 16 2175 (-125 2700)(-7900 2700);
WIRE 16 2175 (-125 2650)(-125 525);
WIRE 16 2175 (-7900 2650)(-125 2650);
WIRE 16 2175 (-125 525)(-7900 525);
WIRE 16 2175 (-7900 525)(-7900 2650);
DOT 1 (-2850 1125);
DOT 1 (-2250 1125);
DOT 1 (-3000 2350);
DOT 1 (-2425 1975);
DOT 1 (-5075 3350);
DOT 1 (-375 1975);
DOT 1 (-2150 2350);
DOT 1 (-625 2350);
DOT 1 (-1125 2350);
DOT 1 (-1125 1975);
DOT 1 (-625 1975);
DOT 1 (-1400 1975);
DOT 1 (-1400 2350);
DOT 1 (-1900 2350);
DOT 1 (-3000 1975);
DOT 1 (-5100 2025);
DOT 1 (-5350 2025);
DOT 1 (-5350 2400);
DOT 1 (-5675 2025);
DOT 1 (-5675 2400);
DOT 1 (-4425 1975);
DOT 1 (-4100 1975);
DOT 1 (-3825 1975);
DOT 1 (-3550 1975);
DOT 1 (-3275 1975);
DOT 1 (-4675 2350);
DOT 1 (-4425 2350);
DOT 1 (-4100 2350);
DOT 1 (-3825 2350);
DOT 1 (-3550 2350);
DOT 1 (-3275 2350);
DOT 1 (-2700 1975);
DOT 1 (-1900 1975);
DOT 1 (-1650 1975);
DOT 1 (-2700 2350);
DOT 1 (-2425 2350);
DOT 1 (-2150 1975);
DOT 1 (-2250 750);
DOT 1 (-5300 1375);
DOT 1 (-5625 1375);
DOT 1 (-6700 2025);
DOT 1 (-6700 725);
DOT 1 (-7050 1100);
DOT 1 (-5925 3975);
DOT 1 (-1950 750);
DOT 1 (-3925 775);
DOT 1 (-4275 1150);
DOT 1 (-3925 1150);
DOT 1 (-3600 775);
DOT 1 (-2850 750);
DOT 1 (-3175 1125);
DOT 1 (-2550 750);
DOT 1 (-2550 1125);
DOT 1 (-6600 2975);
DOT 1 (-5350 3350);
DOT 1 (-975 3600);
DOT 1 (-3825 3600);
DOT 1 (-3375 3600);
DOT 1 (-525 4275);
DOT 1 (-3625 4275);
DOT 1 (-2825 4650);
DOT 1 (-3875 4650);
DOT 1 (-3350 4275);
DOT 1 (-3625 4650);
DOT 1 (-3350 4650);
DOT 1 (-3075 4275);
DOT 1 (-2825 4275);
DOT 1 (-3075 4650);
DOT 1 (-2575 4275);
DOT 1 (-2575 4650);
DOT 1 (-2275 4275);
DOT 1 (-2000 4275);
DOT 1 (-2275 4650);
DOT 1 (-2000 4650);
DOT 1 (-1700 4275);
DOT 1 (-1400 4275);
DOT 1 (-1700 4650);
DOT 1 (-1400 4650);
DOT 1 (-1100 4275);
DOT 1 (-800 4275);
DOT 1 (-1100 4650);
DOT 1 (-800 4650);
DOT 1 (-2525 4050);
DOT 1 (-2150 3600);
DOT 1 (-2150 4050);
DOT 1 (-1700 3600);
DOT 1 (-1700 4050);
DOT 1 (-1375 3600);
DOT 1 (-1375 4050);
DOT 1 (-975 4050);
DOT 1 (-600 3600);
DOT 1 (-4075 3975);
DOT 1 (-3825 3975);
DOT 1 (-3675 2925);
DOT 1 (-3275 2925);
DOT 1 (-2875 2925);
DOT 1 (-3675 3325);
DOT 1 (-3600 3975);
DOT 1 (-3375 3975);
DOT 1 (-3275 3325);
DOT 1 (-3125 3600);
DOT 1 (-3125 3975);
DOT 1 (-2850 3600);
DOT 1 (-5325 4650);
DOT 1 (-4700 3975);
DOT 1 (-5625 4650);
DOT 1 (-5325 3600);
DOT 1 (-5625 4275);
DOT 1 (-4450 2975);
DOT 1 (-6600 3350);
DOT 1 (-7375 4275);
DOT 1 (-6675 4650);
DOT 1 (-7000 3600);
DOT 1 (-5625 3600);
DOT 1 (-5275 700);
DOT 1 (-5950 1075);
DOT 1 (-5975 2400);
DOT 1 (-6700 1100);
DOT 1 (-5600 700);
DOT 1 (-5600 1075);
DOT 1 (-7375 1100);
DOT 1 (-6350 725);
DOT 1 (-4700 3600);
DOT 1 (-7725 4650);
DOT 1 (-6350 4275);
DOT 1 (-7375 725);
DOT 1 (-7725 1100);
DOT 1 (-7725 1750);
DOT 1 (-7375 1750);
DOT 1 (-7050 725);
DOT 1 (-7050 1375);
DOT 1 (-6700 1750);
DOT 1 (-7725 2400);
DOT 1 (-7375 2400);
DOT 1 (-7275 2975);
DOT 1 (-7675 3975);
DOT 1 (-7625 3350);
DOT 1 (-7275 3350);
DOT 1 (-7325 3600);
DOT 1 (-7325 3975);
DOT 1 (-6700 2400);
DOT 1 (-6950 2975);
DOT 1 (-6250 2975);
DOT 1 (-6950 3350);
DOT 1 (-5625 1750);
DOT 1 (-7375 4650);
DOT 1 (-7050 4275);
DOT 1 (-7050 4650);
DOT 1 (-7000 3975);
DOT 1 (-6650 3975);
DOT 1 (-5325 4275);
DOT 1 (-5000 4650);
DOT 1 (-5000 4275);
DOT 1 (-4700 4275);
DOT 1 (-5625 3975);
DOT 1 (-5000 3975);
DOT 1 (-5900 3350);
DOT 1 (-5625 3350);
DOT 1 (-5625 2975);
DOT 1 (-5350 2975);
DOT 1 (-5075 2975);
DOT 1 (-4750 2975);
DOT 1 (-4700 4650);
DOT 1 (-4450 4275);
DOT 1 (-7375 2025);
DOT 1 (-7375 1375);
DOT 1 (-6700 1375);
DOT 1 (-7050 2025);
DOT 1 (-7050 1750);
DOT 1 (-5000 3600);
DOT 1 (-5325 3975);
DOT 1 (-5950 4650);
DOT 1 (-6650 3600);
DOT 1 (-6350 1375);
DOT 1 (-6350 2025);
DOT 1 (-5975 1750);
DOT 1 (-4750 3350);
DOT 1 (-4425 3600);
DOT 1 (-6300 3600);
DOT 1 (-6675 4275);
DOT 1 (-7050 2400);
DOT 1 (-1650 2350);
DOT 1 (-3600 3600);
DOT 1 (-4075 3325);
DOT 1 (-875 2350);
DOT 1 (-875 1975);
FORCENOTE
PVMCP: 22UF, 603, 19X
(-2315 4740) 0;
DISPLAY LEFT (-2315 4740);
PAINT PURPLE (-2315 4740);
FORCENOTE
(DEBUG ONLY)
(-2315 4679) 0;
DISPLAY LEFT (-2315 4679);
DISPLAY 1.021277 (-2315 4679);
PAINT PURPLE (-2315 4679);
FORCENOTE
PVCCIO: 22UF, 603, 6X
(-3790 4065) 0;
DISPLAY LEFT (-3790 4065);
PAINT PURPLE (-3790 4065);
FORCENOTE
PVMCP: 47UF, 805, 17X
(-3590 2540) 0;
DISPLAY LEFT (-3590 2540);
PAINT PURPLE (-3590 2540);
FORCENOTE
(DEBUG ONLY)
(-3565 2479) 0;
DISPLAY LEFT (-3565 2479);
DISPLAY 1.021277 (-3565 2479);
PAINT PURPLE (-3565 2479);
FORCENOTE
PVCCIN: 22UF/603/33X
(-7265 4740) 0;
DISPLAY LEFT (-7265 4740);
PAINT PURPLE (-7265 4740);
FORCENOTE
ROOM = PVCCIN_CPU0_DECAP_VR
(-7890 215) 0;
DISPLAY LEFT (-7890 215);
DISPLAY 2.446809 (-7890 215);
PAINT PURPLE (-7890 215);
FORCENOTE
PVCCIN: 47UF, 805, 25X
(-7290 2490) 0;
DISPLAY LEFT (-7290 2490);
PAINT PURPLE (-7290 2490);
FORCENOTE
FULL CAP CONFIG FOR -P SUPPORT.
(-1940 2890) 0;
DISPLAY LEFT (-1940 2890);
PAINT PURPLE (-1940 2890);
FORCENOTE
FULL CAP CONFIG FOR -P SUPPORT.
(-1440 640) 0;
DISPLAY LEFT (-1440 640);
PAINT PURPLE (-1440 640);
FORCENOTE
PVCCIO: 47UF/805/3X, 22UF/603/2X
(-3090 1165) 0;
DISPLAY LEFT (-3090 1165);
PAINT PURPLE (-3090 1165);
QUIT
